FILE_TYPE = MACRO_DRAWING;
SET COLOR_WIRE YELLOW;
SET COLOR_PROP ORANGE;
SET COLOR_DOT WHITE;
SET COLOR_ARC YELLOW;
SET COLOR_BODY GREEN;
SET COLOR_NOTE PURPLE;
SET PROP_DISPLAY VALUE;
SET PAGE_NUMBER P188;
FORCEADD OFFPAGE..1
(-7700 1850);
FORCEPROP 2 LAST $XR5 216 
J 0
(-8582 1850);
DISPLAY 0.638298 (-8582 1850);
PAINT MONO (-8582 1850);
FORCEPROP 2 LAST $XR4 215 
J 0
(-8462 1850);
DISPLAY 0.638298 (-8462 1850);
PAINT MONO (-8462 1850);
FORCEPROP 2 LAST $XR3 213 
J 0
(-8342 1850);
DISPLAY 0.638298 (-8342 1850);
PAINT MONO (-8342 1850);
FORCEPROP 2 LAST $XR2 212 
J 0
(-8222 1850);
DISPLAY 0.638298 (-8222 1850);
PAINT MONO (-8222 1850);
FORCEPROP 2 LAST $XR1 211 
J 0
(-8102 1850);
DISPLAY 0.638298 (-8102 1850);
PAINT MONO (-8102 1850);
FORCEPROP 2 LAST $XR0 210 
J 0
(-7982 1850);
DISPLAY 0.638298 (-7982 1850);
PAINT MONO (-7982 1850);
FORCEPROP 2 LAST CDS_LIB standard
J 0
(-7700 1850);
DISPLAY INVISIBLE (-7700 1850);
FORCEPROP 1 LAST OFFPAGE TRUE
J 0
(-7375 1725);
DISPLAY 0.872340 (-7375 1725);
PAINT GREEN (-7375 1725);
DISPLAY INVISIBLE (-7375 1725);
FORCEPROP 1 LAST COMMENT_BODY TRUE
J 0
(-7575 1750);
DISPLAY 0.872340 (-7575 1750);
PAINT GREEN (-7575 1750);
DISPLAY INVISIBLE (-7575 1750);
FORCEPROP 2 LAST PATH I1
J 0
(-7950 1900);
DISPLAY 0.680851 (-7950 1900);
DISPLAY INVISIBLE (-7950 1900);
FORCEADD Q_CAP..1
(-7150 2300);
FORCEPROP 1 LAST LOCATION PC125
J 0
(-7100 2400);
DISPLAY 0.489362 (-7100 2400);
PAINT SKYBLUE (-7100 2400);
FORCEPROP 0 LAST $SEC 1
J 0
(-7100 2450);
DISPLAY 0.680851 (-7100 2450);
PAINT MONO (-7100 2450);
DISPLAY INVISIBLE (-7100 2450);
FORCEPROP 0 LAST CDS_SEC 1
J 0
(-7100 2450);
DISPLAY 1.021277 (-7100 2450);
DISPLAY INVISIBLE (-7100 2450);
FORCEPROP 1 LASTPIN (-7150 2400) $PN 1
J 0
(-7140 2380);
DISPLAY 0.489362 (-7140 2380);
PAINT MONO (-7140 2380);
FORCEPROP 1 LASTPIN (-7150 2200) $PN 2
J 0
(-7140 2180);
DISPLAY 0.489362 (-7140 2180);
PAINT MONO (-7140 2180);
FORCEPROP 1 LAST MATERIAL X6S
J 0
(-7100 2200);
DISPLAY 0.489362 (-7100 2200);
PAINT SKYBLUE (-7100 2200);
FORCEPROP 1 LAST TOLERANCE 10%
J 0
(-7100 2250);
DISPLAY 0.489362 (-7100 2250);
PAINT SKYBLUE (-7100 2250);
FORCEPROP 1 LAST VALUE 2.2UF
J 0
(-7100 2350);
DISPLAY 0.489362 (-7100 2350);
PAINT SKYBLUE (-7100 2350);
FORCEPROP 1 LAST VOLTAGE 10V
J 0
(-7100 2300);
DISPLAY 0.489362 (-7100 2300);
PAINT SKYBLUE (-7100 2300);
FORCEPROP 1 LAST PACK_TYPE C0402
J 0
(-7100 2100);
DISPLAY 0.489362 (-7100 2100);
PAINT SKYBLUE (-7100 2100);
FORCEPROP 2 LAST CDS_LIB pure_quanta
J 0
(-7150 2300);
DISPLAY INVISIBLE (-7150 2300);
FORCEPROP 1 LAST PATH I10
J 0
(-7100 2450);
DISPLAY 0.978723 (-7100 2450);
PAINT WHITE (-7100 2450);
DISPLAY INVISIBLE (-7100 2450);
FORCEPROP 1 LAST PART_NUMBER CH5222KEB01
J 0
(-7100 2150);
DISPLAY 0.489362 (-7100 2150);
PAINT SKYBLUE (-7100 2150);
DISPLAY INVISIBLE (-7100 2150);
FORCEADD OFFPAGE..2
R 2
(-6800 1950);
FORCEPROP 2 LAST $XR0 210 
J 0
(-7055 1950);
DISPLAY 0.638298 (-7055 1950);
PAINT MONO (-7055 1950);
FORCEPROP 2 LAST CDS_LIB standard
J 2
(-6800 1950);
DISPLAY INVISIBLE (-6800 1950);
FORCEPROP 1 LAST OFFPAGE TRUE
J 2
(-7125 1825);
DISPLAY 0.872340 (-7125 1825);
PAINT GREEN (-7125 1825);
DISPLAY INVISIBLE (-7125 1825);
FORCEPROP 1 LAST COMMENT_BODY TRUE
J 2
(-6755 1855);
DISPLAY 0.872340 (-6755 1855);
PAINT GREEN (-6755 1855);
DISPLAY INVISIBLE (-6755 1855);
FORCEPROP 2 LAST PATH I11
J 0
(-7050 2000);
DISPLAY 0.680851 (-7050 2000);
DISPLAY INVISIBLE (-7050 2000);
FORCEADD Q_RES..2
(-7150 2850);
FORCEPROP 1 LAST LOCATION PR422
J 0
(-7105 2975);
DISPLAY 0.489362 (-7105 2975);
PAINT SKYBLUE (-7105 2975);
FORCEPROP 0 LAST $SEC 1
J 0
(-7100 3025);
DISPLAY 0.680851 (-7100 3025);
PAINT MONO (-7100 3025);
DISPLAY INVISIBLE (-7100 3025);
FORCEPROP 0 LAST CDS_SEC 1
J 0
(-7100 3025);
DISPLAY 1.021277 (-7100 3025);
DISPLAY INVISIBLE (-7100 3025);
FORCEPROP 1 LASTPIN (-7150 2950) $PN 1
J 0
(-7145 2912);
DISPLAY 0.489362 (-7145 2912);
PAINT MONO (-7145 2912);
FORCEPROP 1 LASTPIN (-7150 2750) $PN 2
J 0
(-7145 2760);
DISPLAY 0.489362 (-7145 2760);
PAINT MONO (-7145 2760);
FORCEPROP 1 LAST PACK_TYPE 0402LF
J 0
(-7100 2675);
DISPLAY 0.489362 (-7100 2675);
PAINT SKYBLUE (-7100 2675);
FORCEPROP 1 LAST VALUE 2.2
J 0
(-7100 2925);
DISPLAY 0.489362 (-7100 2925);
PAINT SKYBLUE (-7100 2925);
FORCEPROP 1 LAST TOLERANCE 1%
J 0
(-7100 2875);
DISPLAY 0.489362 (-7100 2875);
PAINT SKYBLUE (-7100 2875);
FORCEPROP 1 LAST WATTAGE 1/16W
J 0
(-7100 2825);
DISPLAY 0.489362 (-7100 2825);
PAINT SKYBLUE (-7100 2825);
FORCEPROP 1 LAST MATERIAL CHIP
J 0
(-7100 2775);
DISPLAY 0.489362 (-7100 2775);
PAINT SKYBLUE (-7100 2775);
FORCEPROP 2 LAST CDS_LIB pure_quanta
J 0
(-7150 2850);
DISPLAY INVISIBLE (-7150 2850);
FORCEPROP 1 LAST PATH I12
J 0
(-7100 3025);
DISPLAY 0.978723 (-7100 3025);
PAINT WHITE (-7100 3025);
DISPLAY INVISIBLE (-7100 3025);
FORCEPROP 1 LAST PART_NUMBER CS-2202FB01
J 0
(-7100 2725);
DISPLAY 0.489362 (-7100 2725);
PAINT SKYBLUE (-7100 2725);
DISPLAY INVISIBLE (-7100 2725);
FORCEADD UNIVERSAL_GND..1
(-6800 2600);
FORCEPROP 3 LASTPIN (-6800 2650) SIG_NAME GND\g
J 0
(-6790 2660);
DISPLAY 0.659574 (-6790 2660);
PAINT MONO (-6790 2660);
DISPLAY INVISIBLE (-6790 2660);
FORCEPROP 2 LAST CDS_LIB pure_quanta_power
J 0
(-6800 2600);
DISPLAY INVISIBLE (-6800 2600);
FORCEPROP 1 LAST HDL_POWER GND
J 1
(-6775 2525);
DISPLAY 0.872340 (-6775 2525);
PAINT GREEN (-6775 2525);
DISPLAY INVISIBLE (-6775 2525);
FORCEPROP 1 LAST PATH I13
J 0
(-6725 2600);
DISPLAY 0.872340 (-6725 2600);
PAINT AQUA (-6725 2600);
DISPLAY INVISIBLE (-6725 2600);
FORCEADD VCC_CORE..1
(-7150 3250);
FORCEPROP 3 LASTPIN (-7150 3200) SIG_NAME PVDDCR_CPU0_P1_PVCC\g
J 0
(-7140 3210);
DISPLAY 0.659574 (-7140 3210);
PAINT MONO (-7140 3210);
DISPLAY INVISIBLE (-7140 3210);
FORCEPROP 1 LAST HDL_POWER PVDDCR_CPU0_P1_PVCC
J 1
(-7150 3300);
DISPLAY 0.489362 (-7150 3300);
PAINT GREEN (-7150 3300);
FORCEPROP 2 LAST CDS_LIB pure_quanta_power
J 0
(-7150 3250);
DISPLAY INVISIBLE (-7150 3250);
FORCEPROP 1 LAST PATH I14
J 0
(-7100 3275);
DISPLAY 0.872340 (-7100 3275);
PAINT AQUA (-7100 3275);
DISPLAY INVISIBLE (-7100 3275);
FORCEADD Q_CAP..1
(-6800 2875);
FORCEPROP 1 LAST LOCATION PC126_C0P1_6
J 0
(-6750 2975);
DISPLAY 0.489362 (-6750 2975);
PAINT SKYBLUE (-6750 2975);
FORCEPROP 0 LAST $SEC 1
J 0
(-6750 3025);
DISPLAY 0.680851 (-6750 3025);
PAINT MONO (-6750 3025);
DISPLAY INVISIBLE (-6750 3025);
FORCEPROP 0 LAST CDS_SEC 1
J 0
(-6750 3025);
DISPLAY 1.021277 (-6750 3025);
DISPLAY INVISIBLE (-6750 3025);
FORCEPROP 1 LASTPIN (-6800 2975) $PN 1
J 0
(-6790 2955);
DISPLAY 0.489362 (-6790 2955);
PAINT MONO (-6790 2955);
FORCEPROP 1 LASTPIN (-6800 2775) $PN 2
J 0
(-6790 2755);
DISPLAY 0.489362 (-6790 2755);
PAINT MONO (-6790 2755);
FORCEPROP 1 LAST VALUE 2.2UF
J 0
(-6750 2925);
DISPLAY 0.489362 (-6750 2925);
PAINT SKYBLUE (-6750 2925);
FORCEPROP 1 LAST PACK_TYPE C0402
J 0
(-6750 2675);
DISPLAY 0.489362 (-6750 2675);
PAINT SKYBLUE (-6750 2675);
FORCEPROP 1 LAST VOLTAGE 10V
J 0
(-6750 2875);
DISPLAY 0.489362 (-6750 2875);
PAINT SKYBLUE (-6750 2875);
FORCEPROP 1 LAST TOLERANCE 10%
J 0
(-6750 2825);
DISPLAY 0.489362 (-6750 2825);
PAINT SKYBLUE (-6750 2825);
FORCEPROP 1 LAST MATERIAL X6S
J 0
(-6750 2775);
DISPLAY 0.489362 (-6750 2775);
PAINT SKYBLUE (-6750 2775);
FORCEPROP 2 LAST CDS_LIB pure_quanta
J 0
(-6800 2875);
DISPLAY INVISIBLE (-6800 2875);
FORCEPROP 1 LAST PATH I15
J 0
(-6750 3025);
DISPLAY 0.978723 (-6750 3025);
PAINT WHITE (-6750 3025);
DISPLAY INVISIBLE (-6750 3025);
FORCEPROP 1 LAST PART_NUMBER CH5222KEB01
J 0
(-6750 2725);
DISPLAY 0.489362 (-6750 2725);
PAINT SKYBLUE (-6750 2725);
DISPLAY INVISIBLE (-6750 2725);
FORCEADD UNIVERSAL_GND..1
(-7525 4300);
FORCEPROP 3 LASTPIN (-7525 4350) SIG_NAME GND\g
J 0
(-7515 4360);
DISPLAY 0.659574 (-7515 4360);
PAINT MONO (-7515 4360);
DISPLAY INVISIBLE (-7515 4360);
FORCEPROP 2 LAST CDS_LIB pure_quanta_power
J 0
(-7525 4300);
DISPLAY INVISIBLE (-7525 4300);
FORCEPROP 1 LAST HDL_POWER GND
J 1
(-7500 4225);
DISPLAY 0.872340 (-7500 4225);
PAINT GREEN (-7500 4225);
DISPLAY INVISIBLE (-7500 4225);
FORCEPROP 1 LAST PATH I16
J 0
(-7450 4300);
DISPLAY 0.872340 (-7450 4300);
PAINT AQUA (-7450 4300);
DISPLAY INVISIBLE (-7450 4300);
FORCEADD OFFPAGE..1
(-6800 4250);
FORCEPROP 2 LAST $XR0 210 
J 0
(-7082 4250);
DISPLAY 0.638298 (-7082 4250);
PAINT MONO (-7082 4250);
FORCEPROP 2 LAST CDS_LIB standard
J 2
(-6800 4250);
DISPLAY INVISIBLE (-6800 4250);
FORCEPROP 1 LAST OFFPAGE TRUE
J 0
(-6475 4125);
DISPLAY 0.872340 (-6475 4125);
PAINT GREEN (-6475 4125);
DISPLAY INVISIBLE (-6475 4125);
FORCEPROP 1 LAST COMMENT_BODY TRUE
J 0
(-6675 4150);
DISPLAY 0.872340 (-6675 4150);
PAINT GREEN (-6675 4150);
DISPLAY INVISIBLE (-6675 4150);
FORCEPROP 2 LAST PATH I17
J 0
(-7050 4300);
DISPLAY 0.680851 (-7050 4300);
DISPLAY INVISIBLE (-7050 4300);
FORCEADD ISL99390FRZTR5935..1
(-5700 4850);
FORCEPROP 1 LAST LOCATION PU29
J 0
(-6000 5725);
DISPLAY 0.489362 (-6000 5725);
PAINT SKYBLUE (-6000 5725);
FORCEPROP 0 LAST $SEC 1
J 0
(-6000 5875);
DISPLAY 0.680851 (-6000 5875);
PAINT MONO (-6000 5875);
DISPLAY INVISIBLE (-6000 5875);
FORCEPROP 2 LAST CDS_SEC 1
J 0
(-6000 5875);
DISPLAY 1.021277 (-6000 5875);
DISPLAY INVISIBLE (-6000 5875);
FORCEPROP 0 LASTPIN (-5300 4400) $PN 2
J 0
(-5290 4410);
DISPLAY 0.489362 (-5290 4410);
PAINT MONO (-5290 4410);
FORCEPROP 0 LASTPIN (-5300 5200) $PN 33
J 0
(-5290 5210);
DISPLAY 0.489362 (-5290 5210);
PAINT MONO (-5290 5210);
FORCEPROP 0 LASTPIN (-6150 4600) $PN 31
J 2
(-6160 4610);
DISPLAY 0.489362 (-6160 4610);
PAINT MONO (-6160 4610);
FORCEPROP 0 LASTPIN (-6150 5000) $PN 35
J 2
(-6160 5010);
DISPLAY 0.489362 (-6160 5010);
PAINT MONO (-6160 5010);
FORCEPROP 0 LASTPIN (-5300 4550) $PN 6
J 0
(-5290 4560);
DISPLAY 0.489362 (-5290 4560);
PAINT MONO (-5290 4560);
FORCEPROP 0 LASTPIN (-5300 4500) $PN 41
J 0
(-5290 4510);
DISPLAY 0.489362 (-5290 4510);
PAINT MONO (-5290 4510);
FORCEPROP 0 LASTPIN (-6150 4850) $PN 38
J 2
(-6160 4860);
DISPLAY 0.489362 (-6160 4860);
PAINT MONO (-6160 4860);
FORCEPROP 0 LASTPIN (-6150 4550) $PN 37
J 2
(-6160 4560);
DISPLAY 0.489362 (-6160 4560);
PAINT MONO (-6160 4560);
FORCEPROP 0 LASTPIN (-5300 4350) $PN 5
J 0
(-5290 4360);
DISPLAY 0.489362 (-5290 4360);
PAINT MONO (-5290 4360);
FORCEPROP 0 LASTPIN (-5300 4300) $PN 7_9-20_24
J 0
(-5290 4310);
DISPLAY 0.489362 (-5290 4310);
PAINT MONO (-5290 4310);
FORCEPROP 0 LASTPIN (-5300 4250) $PN 40
J 0
(-5290 4260);
DISPLAY 0.489362 (-5290 4260);
PAINT MONO (-5290 4260);
FORCEPROP 0 LASTPIN (-5300 4950) $PN 32
J 0
(-5290 4960);
DISPLAY 0.489362 (-5290 4960);
PAINT MONO (-5290 4960);
FORCEPROP 0 LASTPIN (-6150 5500) $PN 4
J 2
(-6160 5510);
DISPLAY 0.489362 (-6160 5510);
PAINT MONO (-6160 5510);
FORCEPROP 0 LASTPIN (-6150 4250) $PN 34
J 2
(-6160 4260);
DISPLAY 0.489362 (-6160 4260);
PAINT MONO (-6160 4260);
FORCEPROP 0 LASTPIN (-6150 4750) $PN 39
J 2
(-6160 4760);
DISPLAY 0.489362 (-6160 4760);
PAINT MONO (-6160 4760);
FORCEPROP 0 LASTPIN (-5300 4850) $PN 10_19
J 0
(-5290 4860);
DISPLAY 0.489362 (-5290 4860);
PAINT MONO (-5290 4860);
FORCEPROP 0 LASTPIN (-6150 4350) $PN 36
J 2
(-6160 4360);
DISPLAY 0.489362 (-6160 4360);
PAINT MONO (-6160 4360);
FORCEPROP 0 LASTPIN (-6150 5200) $PN 3
J 2
(-6160 5210);
DISPLAY 0.489362 (-6160 5210);
PAINT MONO (-6160 5210);
FORCEPROP 0 LASTPIN (-5300 5500) $PN 25_29
J 0
(-5290 5510);
DISPLAY 0.489362 (-5290 5510);
PAINT MONO (-5290 5510);
FORCEPROP 0 LASTPIN (-5300 5450) $PN 30
J 0
(-5290 5460);
DISPLAY 0.489362 (-5290 5460);
PAINT MONO (-5290 5460);
FORCEPROP 0 LASTPIN (-5300 4600) $PN 1
J 0
(-5290 4610);
DISPLAY 0.489362 (-5290 4610);
PAINT MONO (-5290 4610);
FORCEPROP 2 LAST PART_TYPE SMLF
J 0
(-6000 5825);
DISPLAY 1.021277 (-6000 5825);
FORCEPROP 1 LAST MATERIAL IC
J 0
(-6000 5575);
DISPLAY 0.489362 (-6000 5575);
PAINT SKYBLUE (-6000 5575);
FORCEPROP 2 LAST VALUE ISL99390FRZ-TR5935
J 0
(-6000 5775);
DISPLAY 0.489362 (-6000 5775);
PAINT SKYBLUE (-6000 5775);
FORCEPROP 2 LAST CDS_LIB pure_quanta
J 0
(-5700 4850);
DISPLAY INVISIBLE (-5700 4850);
FORCEPROP 1 LAST NEEDS_NO_SIZE TRUE
J 0
(-5700 4850);
DISPLAY 0.723404 (-5700 4850);
PAINT GREEN (-5700 4850);
DISPLAY INVISIBLE (-5700 4850);
FORCEPROP 1 LAST CDS_LMAN_SYM_OUTLINE -300,700,250,-650
J 0
(-5700 4850);
DISPLAY 0.468085 (-5700 4850);
PAINT GREEN (-5700 4850);
DISPLAY INVISIBLE (-5700 4850);
FORCEPROP 1 LAST PATH I18
J 0
(-5700 4850);
DISPLAY 0.723404 (-5700 4850);
PAINT GREEN (-5700 4850);
DISPLAY INVISIBLE (-5700 4850);
FORCEPROP 1 LAST PART_NUMBER AL099390004
J 0
(-6000 5650);
DISPLAY 0.489362 (-6000 5650);
PAINT SKYBLUE (-6000 5650);
DISPLAY INVISIBLE (-6000 5650);
FORCEADD UNIVERSAL_GND..1
(-5100 1225);
FORCEPROP 3 LASTPIN (-5100 1275) SIG_NAME GND\g
J 0
(-5090 1285);
DISPLAY 0.659574 (-5090 1285);
PAINT MONO (-5090 1285);
DISPLAY INVISIBLE (-5090 1285);
FORCEPROP 2 LAST CDS_LIB pure_quanta_power
J 0
(-5100 1225);
DISPLAY INVISIBLE (-5100 1225);
FORCEPROP 1 LAST HDL_POWER GND
J 1
(-5075 1150);
DISPLAY 0.872340 (-5075 1150);
PAINT GREEN (-5075 1150);
DISPLAY INVISIBLE (-5075 1150);
FORCEPROP 1 LAST PATH I19
J 0
(-5025 1225);
DISPLAY 0.872340 (-5025 1225);
PAINT AQUA (-5025 1225);
DISPLAY INVISIBLE (-5025 1225);
FORCEADD OFFPAGE..1
(-7750 4750);
FORCEPROP 2 LAST $XR5 216 
J 0
(-8602 4750);
DISPLAY 0.638298 (-8602 4750);
PAINT MONO (-8602 4750);
FORCEPROP 2 LAST $XR4 215 
J 0
(-8482 4750);
DISPLAY 0.638298 (-8482 4750);
PAINT MONO (-8482 4750);
FORCEPROP 2 LAST $XR3 213 
J 0
(-8362 4750);
DISPLAY 0.638298 (-8362 4750);
PAINT MONO (-8362 4750);
FORCEPROP 2 LAST $XR2 212 
J 0
(-8242 4750);
DISPLAY 0.638298 (-8242 4750);
PAINT MONO (-8242 4750);
FORCEPROP 2 LAST $XR1 211 
J 0
(-8122 4750);
DISPLAY 0.638298 (-8122 4750);
PAINT MONO (-8122 4750);
FORCEPROP 2 LAST $XR0 210 
J 0
(-8002 4750);
DISPLAY 0.638298 (-8002 4750);
PAINT MONO (-8002 4750);
FORCEPROP 2 LAST CDS_LIB standard
J 0
(-7750 4750);
DISPLAY INVISIBLE (-7750 4750);
FORCEPROP 1 LAST OFFPAGE TRUE
J 0
(-7425 4625);
DISPLAY 0.872340 (-7425 4625);
PAINT GREEN (-7425 4625);
DISPLAY INVISIBLE (-7425 4625);
FORCEPROP 1 LAST COMMENT_BODY TRUE
J 0
(-7625 4650);
DISPLAY 0.872340 (-7625 4650);
PAINT GREEN (-7625 4650);
DISPLAY INVISIBLE (-7625 4650);
FORCEPROP 2 LAST PATH I2
J 0
(-8025 4800);
DISPLAY 0.680851 (-8025 4800);
DISPLAY INVISIBLE (-8025 4800);
FORCEADD UNIVERSAL_GND..1
(-4225 1025);
FORCEPROP 3 LASTPIN (-4225 1075) SIG_NAME GND\g
J 0
(-4215 1085);
DISPLAY 0.659574 (-4215 1085);
PAINT MONO (-4215 1085);
DISPLAY INVISIBLE (-4215 1085);
FORCEPROP 2 LAST CDS_LIB pure_quanta_power
J 0
(-4225 1025);
DISPLAY INVISIBLE (-4225 1025);
FORCEPROP 1 LAST HDL_POWER GND
J 1
(-4200 950);
DISPLAY 0.872340 (-4200 950);
PAINT GREEN (-4200 950);
DISPLAY INVISIBLE (-4200 950);
FORCEPROP 1 LAST PATH I20
J 0
(-4150 1025);
DISPLAY 0.872340 (-4150 1025);
PAINT AQUA (-4150 1025);
DISPLAY INVISIBLE (-4150 1025);
FORCEADD Q_RES..2
(-4225 1250);
FORCEPROP 1 LAST LOCATION PR524
J 0
(-4180 1375);
DISPLAY 0.489362 (-4180 1375);
PAINT SKYBLUE (-4180 1375);
FORCEPROP 0 LAST $SEC 1
J 0
(-4175 1425);
DISPLAY 0.680851 (-4175 1425);
PAINT MONO (-4175 1425);
DISPLAY INVISIBLE (-4175 1425);
FORCEPROP 0 LAST CDS_SEC 1
J 0
(-4175 1425);
DISPLAY 1.021277 (-4175 1425);
DISPLAY INVISIBLE (-4175 1425);
FORCEPROP 1 LASTPIN (-4225 1350) $PN 1
J 0
(-4220 1312);
DISPLAY 0.489362 (-4220 1312);
PAINT MONO (-4220 1312);
FORCEPROP 1 LASTPIN (-4225 1150) $PN 2
J 0
(-4220 1160);
DISPLAY 0.489362 (-4220 1160);
PAINT MONO (-4220 1160);
FORCEPROP 1 LAST WATTAGE 1/8W
J 0
(-4185 1225);
DISPLAY 0.489362 (-4185 1225);
PAINT SKYBLUE (-4185 1225);
FORCEPROP 1 LAST MATERIAL EMPTY
J 0
(-4185 1175);
DISPLAY 0.489362 (-4185 1175);
PAINT RED (-4185 1175);
FORCEPROP 1 LAST VALUE 1.5
J 0
(-4180 1325);
DISPLAY 0.489362 (-4180 1325);
PAINT SKYBLUE (-4180 1325);
FORCEPROP 1 LAST PACK_TYPE 0402LF
J 0
(-4185 1075);
DISPLAY 0.489362 (-4185 1075);
PAINT SKYBLUE (-4185 1075);
FORCEPROP 1 LAST TOLERANCE 1%
J 0
(-4180 1275);
DISPLAY 0.489362 (-4180 1275);
PAINT SKYBLUE (-4180 1275);
FORCEPROP 2 LAST CDS_LIB pure_quanta
J 0
(-4225 1250);
DISPLAY INVISIBLE (-4225 1250);
FORCEPROP 1 LAST PATH I21
J 0
(-4175 1425);
DISPLAY 0.978723 (-4175 1425);
PAINT WHITE (-4175 1425);
DISPLAY INVISIBLE (-4175 1425);
FORCEPROP 1 LAST PART_NUMBER CS-1504FB00
J 0
(-4185 1125);
DISPLAY 0.489362 (-4185 1125);
PAINT SKYBLUE (-4185 1125);
DISPLAY INVISIBLE (-4185 1125);
FORCEADD Q_RES..1
(-3825 900);
FORCEPROP 1 LAST LOCATION PR425
J 0
(-3850 950);
DISPLAY 0.489362 (-3850 950);
PAINT SKYBLUE (-3850 950);
FORCEPROP 0 LAST $SEC 1
J 0
(-3825 975);
DISPLAY 0.680851 (-3825 975);
PAINT MONO (-3825 975);
DISPLAY INVISIBLE (-3825 975);
FORCEPROP 0 LAST CDS_SEC 1
J 0
(-3825 975);
DISPLAY 1.021277 (-3825 975);
DISPLAY INVISIBLE (-3825 975);
FORCEPROP 1 LASTPIN (-3925 900) $PN 1
J 0
(-3913 912);
DISPLAY 0.489362 (-3913 912);
PAINT MONO (-3913 912);
FORCEPROP 1 LASTPIN (-3725 900) $PN 2
J 0
(-3763 912);
DISPLAY 0.489362 (-3763 912);
PAINT MONO (-3763 912);
FORCEPROP 1 LAST PACK_TYPE 0402LF
J 0
(-3725 800);
DISPLAY 0.489362 (-3725 800);
PAINT SKYBLUE (-3725 800);
FORCEPROP 1 LAST VALUE 0
J 2
(-3950 925);
DISPLAY 0.489362 (-3950 925);
PAINT SKYBLUE (-3950 925);
FORCEPROP 1 LAST MATERIAL CHIP
J 0
(-4075 800);
DISPLAY 0.489362 (-4075 800);
PAINT SKYBLUE (-4075 800);
FORCEPROP 1 LAST WATTAGE 1/16W
J 0
(-3725 850);
DISPLAY 0.489362 (-3725 850);
PAINT SKYBLUE (-3725 850);
FORCEPROP 1 LAST TOLERANCE 5%
J 0
(-3700 925);
DISPLAY 0.489362 (-3700 925);
PAINT SKYBLUE (-3700 925);
FORCEPROP 2 LAST CDS_LIB pure_quanta
J 0
(-3825 900);
DISPLAY INVISIBLE (-3825 900);
FORCEPROP 1 LAST PATH I22
J 0
(-3875 1050);
DISPLAY 0.978723 (-3875 1050);
PAINT WHITE (-3875 1050);
DISPLAY INVISIBLE (-3875 1050);
FORCEPROP 1 LAST PART_NUMBER CS00002JB13
J 0
(-4075 850);
DISPLAY 0.489362 (-4075 850);
PAINT SKYBLUE (-4075 850);
DISPLAY INVISIBLE (-4075 850);
FORCEADD Q_CAP..1
(-4225 1750);
FORCEPROP 1 LAST LOCATION PC321
J 0
(-4175 1850);
DISPLAY 0.489362 (-4175 1850);
PAINT SKYBLUE (-4175 1850);
FORCEPROP 0 LAST $SEC 1
J 0
(-4175 1900);
DISPLAY 0.680851 (-4175 1900);
PAINT MONO (-4175 1900);
DISPLAY INVISIBLE (-4175 1900);
FORCEPROP 0 LAST CDS_SEC 1
J 0
(-4175 1900);
DISPLAY 1.021277 (-4175 1900);
DISPLAY INVISIBLE (-4175 1900);
FORCEPROP 1 LASTPIN (-4225 1850) $PN 1
J 0
(-4215 1830);
DISPLAY 0.489362 (-4215 1830);
PAINT MONO (-4215 1830);
FORCEPROP 1 LASTPIN (-4225 1650) $PN 2
J 0
(-4215 1630);
DISPLAY 0.489362 (-4215 1630);
PAINT MONO (-4215 1630);
FORCEPROP 1 LAST MATERIAL EMPTY
J 0
(-4175 1650);
DISPLAY 0.489362 (-4175 1650);
PAINT RED (-4175 1650);
FORCEPROP 1 LAST VOLTAGE 50V
J 0
(-4175 1750);
DISPLAY 0.489362 (-4175 1750);
PAINT SKYBLUE (-4175 1750);
FORCEPROP 1 LAST VALUE 560PF
J 0
(-4175 1800);
DISPLAY 0.489362 (-4175 1800);
PAINT SKYBLUE (-4175 1800);
FORCEPROP 1 LAST TOLERANCE 10%
J 0
(-4175 1700);
DISPLAY 0.489362 (-4175 1700);
PAINT SKYBLUE (-4175 1700);
FORCEPROP 1 LAST PACK_TYPE C0402
J 0
(-4175 1550);
DISPLAY 0.489362 (-4175 1550);
PAINT SKYBLUE (-4175 1550);
FORCEPROP 2 LAST CDS_LIB pure_quanta
J 0
(-4225 1750);
DISPLAY INVISIBLE (-4225 1750);
FORCEPROP 1 LAST PATH I23
J 0
(-4175 1900);
DISPLAY 0.978723 (-4175 1900);
PAINT WHITE (-4175 1900);
DISPLAY INVISIBLE (-4175 1900);
FORCEPROP 1 LAST PART_NUMBER CH1566K1B09
J 0
(-4175 1600);
DISPLAY 0.489362 (-4175 1600);
PAINT SKYBLUE (-4175 1600);
DISPLAY INVISIBLE (-4175 1600);
FORCEADD UNIVERSAL_GND..1
(-3700 1575);
FORCEPROP 3 LASTPIN (-3700 1625) SIG_NAME GND\g
J 0
(-3690 1635);
DISPLAY 0.659574 (-3690 1635);
PAINT MONO (-3690 1635);
DISPLAY INVISIBLE (-3690 1635);
FORCEPROP 2 LAST CDS_LIB pure_quanta_power
J 0
(-3700 1575);
DISPLAY INVISIBLE (-3700 1575);
FORCEPROP 1 LAST HDL_POWER GND
J 1
(-3675 1500);
DISPLAY 0.872340 (-3675 1500);
PAINT GREEN (-3675 1500);
DISPLAY INVISIBLE (-3675 1500);
FORCEPROP 1 LAST PATH I24
J 0
(-3625 1575);
DISPLAY 0.872340 (-3625 1575);
PAINT AQUA (-3625 1575);
DISPLAY INVISIBLE (-3625 1575);
FORCEADD Q_CAP..1
(-4900 2825);
FORCEPROP 1 LAST LOCATION PC127_6
J 0
(-4850 2925);
DISPLAY 0.489362 (-4850 2925);
PAINT SKYBLUE (-4850 2925);
FORCEPROP 0 LAST $SEC 1
J 0
(-4850 2975);
DISPLAY 0.680851 (-4850 2975);
PAINT MONO (-4850 2975);
DISPLAY INVISIBLE (-4850 2975);
FORCEPROP 0 LAST CDS_SEC 1
J 0
(-4850 2975);
DISPLAY 1.021277 (-4850 2975);
DISPLAY INVISIBLE (-4850 2975);
FORCEPROP 1 LASTPIN (-4900 2925) $PN 1
J 0
(-4890 2905);
DISPLAY 0.489362 (-4890 2905);
PAINT MONO (-4890 2905);
FORCEPROP 1 LASTPIN (-4900 2725) $PN 2
J 0
(-4890 2705);
DISPLAY 0.489362 (-4890 2705);
PAINT MONO (-4890 2705);
FORCEPROP 1 LAST PACK_TYPE 0402
J 0
(-4850 2625);
DISPLAY 0.489362 (-4850 2625);
PAINT SKYBLUE (-4850 2625);
FORCEPROP 1 LAST VOLTAGE 25V
J 0
(-4850 2825);
DISPLAY 0.489362 (-4850 2825);
PAINT SKYBLUE (-4850 2825);
FORCEPROP 1 LAST MATERIAL X7R
J 0
(-4850 2725);
DISPLAY 0.489362 (-4850 2725);
PAINT SKYBLUE (-4850 2725);
FORCEPROP 1 LAST TOLERANCE 10%
J 0
(-4850 2775);
DISPLAY 0.489362 (-4850 2775);
PAINT SKYBLUE (-4850 2775);
FORCEPROP 1 LAST VALUE 0.1UF
J 0
(-4850 2875);
DISPLAY 0.489362 (-4850 2875);
PAINT SKYBLUE (-4850 2875);
FORCEPROP 2 LAST CDS_LIB pure_quanta
J 0
(-4900 2825);
DISPLAY INVISIBLE (-4900 2825);
FORCEPROP 1 LAST PATH I25
J 0
(-4850 2975);
DISPLAY 0.978723 (-4850 2975);
PAINT WHITE (-4850 2975);
DISPLAY INVISIBLE (-4850 2975);
FORCEPROP 1 LAST PART_NUMBER CH4104K1B00
J 0
(-4850 2675);
DISPLAY 0.489362 (-4850 2675);
PAINT SKYBLUE (-4850 2675);
DISPLAY INVISIBLE (-4850 2675);
FORCEADD UNIVERSAL_GND..1
(-5150 4125);
FORCEPROP 3 LASTPIN (-5150 4175) SIG_NAME GND\g
J 0
(-5140 4185);
DISPLAY 0.659574 (-5140 4185);
PAINT MONO (-5140 4185);
DISPLAY INVISIBLE (-5140 4185);
FORCEPROP 2 LAST CDS_LIB pure_quanta_power
J 0
(-5150 4125);
DISPLAY INVISIBLE (-5150 4125);
FORCEPROP 1 LAST HDL_POWER GND
J 1
(-5125 4050);
DISPLAY 0.872340 (-5125 4050);
PAINT GREEN (-5125 4050);
DISPLAY INVISIBLE (-5125 4050);
FORCEPROP 1 LAST PATH I26
J 0
(-5075 4125);
DISPLAY 0.872340 (-5075 4125);
PAINT AQUA (-5075 4125);
DISPLAY INVISIBLE (-5075 4125);
FORCEADD Q_CAP..1
(-4525 2825);
FORCEPROP 1 LAST LOCATION PC128_6
J 0
(-4475 2925);
DISPLAY 0.489362 (-4475 2925);
PAINT SKYBLUE (-4475 2925);
FORCEPROP 0 LAST $SEC 1
J 0
(-4475 2950);
DISPLAY 0.680851 (-4475 2950);
PAINT MONO (-4475 2950);
DISPLAY INVISIBLE (-4475 2950);
FORCEPROP 0 LAST CDS_SEC 1
J 0
(-4475 2950);
DISPLAY 1.021277 (-4475 2950);
DISPLAY INVISIBLE (-4475 2950);
FORCEPROP 1 LASTPIN (-4525 2925) $PN 1
J 0
(-4515 2905);
DISPLAY 0.489362 (-4515 2905);
PAINT MONO (-4515 2905);
FORCEPROP 1 LASTPIN (-4525 2725) $PN 2
J 0
(-4515 2705);
DISPLAY 0.489362 (-4515 2705);
PAINT MONO (-4515 2705);
FORCEPROP 1 LAST PACK_TYPE C0402
J 0
(-4475 2625);
DISPLAY 0.489362 (-4475 2625);
PAINT SKYBLUE (-4475 2625);
FORCEPROP 1 LAST MATERIAL X6S
J 0
(-4475 2725);
DISPLAY 0.489362 (-4475 2725);
PAINT SKYBLUE (-4475 2725);
FORCEPROP 1 LAST TOLERANCE 10%
J 0
(-4475 2775);
DISPLAY 0.489362 (-4475 2775);
PAINT SKYBLUE (-4475 2775);
FORCEPROP 1 LAST VOLTAGE 25V
J 0
(-4475 2825);
DISPLAY 0.489362 (-4475 2825);
PAINT SKYBLUE (-4475 2825);
FORCEPROP 1 LAST VALUE 1UF
J 0
(-4475 2875);
DISPLAY 0.489362 (-4475 2875);
PAINT SKYBLUE (-4475 2875);
FORCEPROP 2 LAST CDS_LIB pure_quanta
J 0
(-4525 2825);
DISPLAY INVISIBLE (-4525 2825);
FORCEPROP 1 LAST PATH I27
J 0
(-4475 2975);
DISPLAY 0.978723 (-4475 2975);
PAINT WHITE (-4475 2975);
DISPLAY INVISIBLE (-4475 2975);
FORCEPROP 1 LAST PART_NUMBER CH5104KEB02
J 0
(-4475 2675);
DISPLAY 0.489362 (-4475 2675);
PAINT SKYBLUE (-4475 2675);
DISPLAY INVISIBLE (-4475 2675);
FORCEADD Q_RES..1
(-4250 2300);
FORCEPROP 1 LAST LOCATION PR424
J 0
(-4275 2350);
DISPLAY 0.489362 (-4275 2350);
PAINT SKYBLUE (-4275 2350);
FORCEPROP 0 LAST $SEC 1
J 0
(-4225 2375);
DISPLAY 0.680851 (-4225 2375);
PAINT MONO (-4225 2375);
DISPLAY INVISIBLE (-4225 2375);
FORCEPROP 0 LAST CDS_SEC 1
J 0
(-4225 2375);
DISPLAY 1.021277 (-4225 2375);
DISPLAY INVISIBLE (-4225 2375);
FORCEPROP 1 LASTPIN (-4350 2300) $PN 1
J 0
(-4338 2312);
DISPLAY 0.489362 (-4338 2312);
PAINT MONO (-4338 2312);
FORCEPROP 1 LASTPIN (-4150 2300) $PN 2
J 0
(-4188 2312);
DISPLAY 0.489362 (-4188 2312);
PAINT MONO (-4188 2312);
FORCEPROP 1 LAST VALUE 5.6
J 2
(-4350 2325);
DISPLAY 0.489362 (-4350 2325);
PAINT SKYBLUE (-4350 2325);
FORCEPROP 1 LAST WATTAGE 1/16W
J 0
(-4150 2250);
DISPLAY 0.489362 (-4150 2250);
PAINT SKYBLUE (-4150 2250);
FORCEPROP 1 LAST PACK_TYPE 0402LF
J 0
(-4150 2200);
DISPLAY 0.489362 (-4150 2200);
PAINT SKYBLUE (-4150 2200);
FORCEPROP 1 LAST TOLERANCE 1%
J 0
(-4150 2325);
DISPLAY 0.489362 (-4150 2325);
PAINT SKYBLUE (-4150 2325);
FORCEPROP 1 LAST MATERIAL CHIP
J 0
(-4500 2200);
DISPLAY 0.489362 (-4500 2200);
PAINT SKYBLUE (-4500 2200);
FORCEPROP 2 LAST CDS_LIB pure_quanta
J 0
(-4250 2300);
DISPLAY INVISIBLE (-4250 2300);
FORCEPROP 1 LAST PATH I28
J 0
(-4300 2450);
DISPLAY 0.978723 (-4300 2450);
PAINT WHITE (-4300 2450);
DISPLAY INVISIBLE (-4300 2450);
FORCEPROP 1 LAST PART_NUMBER CS-5602FB01
J 0
(-4500 2250);
DISPLAY 0.489362 (-4500 2250);
PAINT SKYBLUE (-4500 2250);
DISPLAY INVISIBLE (-4500 2250);
FORCEADD Q_CAP..1
(-4200 2825);
FORCEPROP 1 LAST LOCATION PC129_6
J 0
(-4150 2925);
DISPLAY 0.489362 (-4150 2925);
PAINT SKYBLUE (-4150 2925);
FORCEPROP 0 LAST $SEC 1
J 0
(-4150 2950);
DISPLAY 0.680851 (-4150 2950);
PAINT MONO (-4150 2950);
DISPLAY INVISIBLE (-4150 2950);
FORCEPROP 0 LAST CDS_SEC 1
J 0
(-4150 2950);
DISPLAY 1.021277 (-4150 2950);
DISPLAY INVISIBLE (-4150 2950);
FORCEPROP 1 LASTPIN (-4200 2925) $PN 1
J 0
(-4190 2905);
DISPLAY 0.489362 (-4190 2905);
PAINT MONO (-4190 2905);
FORCEPROP 1 LASTPIN (-4200 2725) $PN 2
J 0
(-4190 2705);
DISPLAY 0.489362 (-4190 2705);
PAINT MONO (-4190 2705);
FORCEPROP 1 LAST PACK_TYPE C0805
J 0
(-4150 2625);
DISPLAY 0.489362 (-4150 2625);
PAINT SKYBLUE (-4150 2625);
FORCEPROP 1 LAST MATERIAL X6S
J 0
(-4150 2725);
DISPLAY 0.489362 (-4150 2725);
PAINT SKYBLUE (-4150 2725);
FORCEPROP 1 LAST VALUE 22UF
J 0
(-4150 2875);
DISPLAY 0.489362 (-4150 2875);
PAINT SKYBLUE (-4150 2875);
FORCEPROP 1 LAST VOLTAGE 16V
J 0
(-4150 2825);
DISPLAY 0.489362 (-4150 2825);
PAINT SKYBLUE (-4150 2825);
FORCEPROP 1 LAST TOLERANCE 20%
J 0
(-4150 2775);
DISPLAY 0.489362 (-4150 2775);
PAINT SKYBLUE (-4150 2775);
FORCEPROP 2 LAST CDS_LIB pure_quanta
J 0
(-4200 2825);
DISPLAY INVISIBLE (-4200 2825);
FORCEPROP 1 LAST PATH I29
J 0
(-4150 2975);
DISPLAY 0.978723 (-4150 2975);
PAINT WHITE (-4150 2975);
DISPLAY INVISIBLE (-4150 2975);
FORCEPROP 1 LAST PART_NUMBER CH6223MEA01
J 0
(-4150 2675);
DISPLAY 0.489362 (-4150 2675);
PAINT SKYBLUE (-4150 2675);
DISPLAY INVISIBLE (-4150 2675);
FORCEADD UNIVERSAL_GND..1
(-7475 1400);
FORCEPROP 3 LASTPIN (-7475 1450) SIG_NAME GND\g
J 0
(-7465 1460);
DISPLAY 0.659574 (-7465 1460);
PAINT MONO (-7465 1460);
DISPLAY INVISIBLE (-7465 1460);
FORCEPROP 2 LAST CDS_LIB pure_quanta_power
J 0
(-7475 1400);
DISPLAY INVISIBLE (-7475 1400);
FORCEPROP 1 LAST HDL_POWER GND
J 1
(-7450 1325);
DISPLAY 0.872340 (-7450 1325);
PAINT GREEN (-7450 1325);
DISPLAY INVISIBLE (-7450 1325);
FORCEPROP 1 LAST PATH I3
J 0
(-7400 1400);
DISPLAY 0.872340 (-7400 1400);
PAINT AQUA (-7400 1400);
DISPLAY INVISIBLE (-7400 1400);
FORCEADD Q_CAP..1
(-3875 2825);
FORCEPROP 1 LAST LOCATION PC130_6
J 0
(-3825 2925);
DISPLAY 0.489362 (-3825 2925);
PAINT SKYBLUE (-3825 2925);
FORCEPROP 0 LAST $SEC 1
J 0
(-3825 2950);
DISPLAY 0.680851 (-3825 2950);
PAINT MONO (-3825 2950);
DISPLAY INVISIBLE (-3825 2950);
FORCEPROP 0 LAST CDS_SEC 1
J 0
(-3825 2950);
DISPLAY 1.021277 (-3825 2950);
DISPLAY INVISIBLE (-3825 2950);
FORCEPROP 1 LASTPIN (-3875 2925) $PN 1
J 0
(-3865 2905);
DISPLAY 0.489362 (-3865 2905);
PAINT MONO (-3865 2905);
FORCEPROP 1 LASTPIN (-3875 2725) $PN 2
J 0
(-3865 2705);
DISPLAY 0.489362 (-3865 2705);
PAINT MONO (-3865 2705);
FORCEPROP 1 LAST PACK_TYPE C0805
J 0
(-3825 2625);
DISPLAY 0.489362 (-3825 2625);
PAINT SKYBLUE (-3825 2625);
FORCEPROP 1 LAST MATERIAL X6S
J 0
(-3825 2725);
DISPLAY 0.489362 (-3825 2725);
PAINT SKYBLUE (-3825 2725);
FORCEPROP 1 LAST VALUE 22UF
J 0
(-3825 2875);
DISPLAY 0.489362 (-3825 2875);
PAINT SKYBLUE (-3825 2875);
FORCEPROP 1 LAST VOLTAGE 16V
J 0
(-3825 2825);
DISPLAY 0.489362 (-3825 2825);
PAINT SKYBLUE (-3825 2825);
FORCEPROP 1 LAST TOLERANCE 20%
J 0
(-3825 2775);
DISPLAY 0.489362 (-3825 2775);
PAINT SKYBLUE (-3825 2775);
FORCEPROP 2 LAST CDS_LIB pure_quanta
J 0
(-3875 2825);
DISPLAY INVISIBLE (-3875 2825);
FORCEPROP 1 LAST PATH I30
J 0
(-3825 2975);
DISPLAY 0.978723 (-3825 2975);
PAINT WHITE (-3825 2975);
DISPLAY INVISIBLE (-3825 2975);
FORCEPROP 1 LAST PART_NUMBER CH6223MEA01
J 0
(-3825 2675);
DISPLAY 0.489362 (-3825 2675);
PAINT SKYBLUE (-3825 2675);
DISPLAY INVISIBLE (-3825 2675);
FORCEADD UNIVERSAL_GND..1
(-4275 3900);
FORCEPROP 3 LASTPIN (-4275 3950) SIG_NAME GND\g
J 0
(-4265 3960);
DISPLAY 0.659574 (-4265 3960);
PAINT MONO (-4265 3960);
DISPLAY INVISIBLE (-4265 3960);
FORCEPROP 2 LAST CDS_LIB pure_quanta_power
J 0
(-4275 3900);
DISPLAY INVISIBLE (-4275 3900);
FORCEPROP 1 LAST HDL_POWER GND
J 1
(-4250 3825);
DISPLAY 0.872340 (-4250 3825);
PAINT GREEN (-4250 3825);
DISPLAY INVISIBLE (-4250 3825);
FORCEPROP 1 LAST PATH I31
J 0
(-4200 3900);
DISPLAY 0.872340 (-4200 3900);
PAINT AQUA (-4200 3900);
DISPLAY INVISIBLE (-4200 3900);
FORCEADD Q_RES..2
(-4275 4125);
FORCEPROP 1 LAST LOCATION PR46
J 0
(-4230 4250);
DISPLAY 0.489362 (-4230 4250);
PAINT SKYBLUE (-4230 4250);
FORCEPROP 0 LAST $SEC 1
J 0
(-4225 4300);
DISPLAY 0.680851 (-4225 4300);
PAINT MONO (-4225 4300);
DISPLAY INVISIBLE (-4225 4300);
FORCEPROP 0 LAST CDS_SEC 1
J 0
(-4225 4300);
DISPLAY 1.021277 (-4225 4300);
DISPLAY INVISIBLE (-4225 4300);
FORCEPROP 1 LASTPIN (-4275 4225) $PN 1
J 0
(-4270 4187);
DISPLAY 0.489362 (-4270 4187);
PAINT MONO (-4270 4187);
FORCEPROP 1 LASTPIN (-4275 4025) $PN 2
J 0
(-4270 4035);
DISPLAY 0.489362 (-4270 4035);
PAINT MONO (-4270 4035);
FORCEPROP 1 LAST WATTAGE 1/8W
J 0
(-4235 4100);
DISPLAY 0.489362 (-4235 4100);
PAINT SKYBLUE (-4235 4100);
FORCEPROP 1 LAST MATERIAL EMPTY
J 0
(-4235 4050);
DISPLAY 0.489362 (-4235 4050);
PAINT RED (-4235 4050);
FORCEPROP 1 LAST TOLERANCE 1%
J 0
(-4230 4150);
DISPLAY 0.489362 (-4230 4150);
PAINT SKYBLUE (-4230 4150);
FORCEPROP 1 LAST VALUE 1.5
J 0
(-4230 4200);
DISPLAY 0.489362 (-4230 4200);
PAINT SKYBLUE (-4230 4200);
FORCEPROP 1 LAST PACK_TYPE 0402LF
J 0
(-4235 3950);
DISPLAY 0.489362 (-4235 3950);
PAINT SKYBLUE (-4235 3950);
FORCEPROP 2 LAST CDS_LIB pure_quanta
J 0
(-4275 4125);
DISPLAY INVISIBLE (-4275 4125);
FORCEPROP 1 LAST PATH I32
J 0
(-4225 4300);
DISPLAY 0.978723 (-4225 4300);
PAINT WHITE (-4225 4300);
DISPLAY INVISIBLE (-4225 4300);
FORCEPROP 1 LAST PART_NUMBER CS-1504FB00
J 0
(-4235 4000);
DISPLAY 0.489362 (-4235 4000);
PAINT SKYBLUE (-4235 4000);
DISPLAY INVISIBLE (-4235 4000);
FORCEADD Q_RES..1
(-3925 3750);
FORCEPROP 1 LAST LOCATION PR204
J 0
(-3950 3800);
DISPLAY 0.489362 (-3950 3800);
PAINT SKYBLUE (-3950 3800);
FORCEPROP 0 LAST $SEC 1
J 0
(-3925 3825);
DISPLAY 0.680851 (-3925 3825);
PAINT MONO (-3925 3825);
DISPLAY INVISIBLE (-3925 3825);
FORCEPROP 0 LAST CDS_SEC 1
J 0
(-3925 3825);
DISPLAY 1.021277 (-3925 3825);
DISPLAY INVISIBLE (-3925 3825);
FORCEPROP 1 LASTPIN (-4025 3750) $PN 1
J 0
(-4013 3762);
DISPLAY 0.489362 (-4013 3762);
PAINT MONO (-4013 3762);
FORCEPROP 1 LASTPIN (-3825 3750) $PN 2
J 0
(-3863 3762);
DISPLAY 0.489362 (-3863 3762);
PAINT MONO (-3863 3762);
FORCEPROP 1 LAST VALUE 0
J 2
(-4050 3775);
DISPLAY 0.489362 (-4050 3775);
PAINT SKYBLUE (-4050 3775);
FORCEPROP 1 LAST MATERIAL CHIP
J 0
(-4175 3650);
DISPLAY 0.489362 (-4175 3650);
PAINT SKYBLUE (-4175 3650);
FORCEPROP 1 LAST PACK_TYPE 0402LF
J 0
(-3825 3650);
DISPLAY 0.489362 (-3825 3650);
PAINT SKYBLUE (-3825 3650);
FORCEPROP 1 LAST WATTAGE 1/16W
J 0
(-3825 3700);
DISPLAY 0.489362 (-3825 3700);
PAINT SKYBLUE (-3825 3700);
FORCEPROP 1 LAST TOLERANCE 5%
J 0
(-3800 3775);
DISPLAY 0.489362 (-3800 3775);
PAINT SKYBLUE (-3800 3775);
FORCEPROP 2 LAST CDS_LIB pure_quanta
J 0
(-3925 3750);
DISPLAY INVISIBLE (-3925 3750);
FORCEPROP 1 LAST PATH I33
J 0
(-3975 3900);
DISPLAY 0.978723 (-3975 3900);
PAINT WHITE (-3975 3900);
DISPLAY INVISIBLE (-3975 3900);
FORCEPROP 1 LAST PART_NUMBER CS00002JB13
J 0
(-4175 3700);
DISPLAY 0.489362 (-4175 3700);
PAINT SKYBLUE (-4175 3700);
DISPLAY INVISIBLE (-4175 3700);
FORCEADD Q_CAP..1
(-7525 4575);
FORCEPROP 1 LAST LOCATION PC306_5
J 0
(-7475 4675);
DISPLAY 0.489362 (-7475 4675);
PAINT SKYBLUE (-7475 4675);
FORCEPROP 0 LAST $SEC 1
J 0
(-7475 4700);
DISPLAY 0.680851 (-7475 4700);
PAINT MONO (-7475 4700);
DISPLAY INVISIBLE (-7475 4700);
FORCEPROP 0 LAST CDS_SEC 1
J 0
(-7475 4700);
DISPLAY 1.021277 (-7475 4700);
DISPLAY INVISIBLE (-7475 4700);
FORCEPROP 1 LASTPIN (-7525 4675) $PN 1
J 0
(-7515 4655);
DISPLAY 0.489362 (-7515 4655);
PAINT MONO (-7515 4655);
FORCEPROP 1 LASTPIN (-7525 4475) $PN 2
J 0
(-7515 4455);
DISPLAY 0.489362 (-7515 4455);
PAINT MONO (-7515 4455);
FORCEPROP 1 LAST PACK_TYPE 0402
J 0
(-7475 4375);
DISPLAY 0.489362 (-7475 4375);
PAINT SKYBLUE (-7475 4375);
FORCEPROP 1 LAST MATERIAL X7R
J 0
(-7475 4475);
DISPLAY 0.489362 (-7475 4475);
PAINT SKYBLUE (-7475 4475);
FORCEPROP 1 LAST TOLERANCE 10%
J 0
(-7475 4525);
DISPLAY 0.489362 (-7475 4525);
PAINT SKYBLUE (-7475 4525);
FORCEPROP 1 LAST VOLTAGE 25V
J 0
(-7475 4575);
DISPLAY 0.489362 (-7475 4575);
PAINT SKYBLUE (-7475 4575);
FORCEPROP 1 LAST VALUE 0.1UF
J 0
(-7475 4625);
DISPLAY 0.489362 (-7475 4625);
PAINT SKYBLUE (-7475 4625);
FORCEPROP 2 LAST CDS_LIB pure_quanta
J 0
(-7525 4575);
DISPLAY INVISIBLE (-7525 4575);
FORCEPROP 1 LAST PATH I34
J 0
(-7475 4725);
DISPLAY 0.978723 (-7475 4725);
PAINT WHITE (-7475 4725);
DISPLAY INVISIBLE (-7475 4725);
FORCEPROP 1 LAST PART_NUMBER CH4104K1B00
J 0
(-7475 4425);
DISPLAY 0.489362 (-7475 4425);
PAINT SKYBLUE (-7475 4425);
DISPLAY INVISIBLE (-7475 4425);
FORCEADD UNIVERSAL_GND..1
(-7200 4375);
FORCEPROP 3 LASTPIN (-7200 4425) SIG_NAME GND\g
J 0
(-7190 4435);
DISPLAY 0.659574 (-7190 4435);
PAINT MONO (-7190 4435);
DISPLAY INVISIBLE (-7190 4435);
FORCEPROP 2 LAST CDS_LIB pure_quanta_power
J 0
(-7200 4375);
DISPLAY INVISIBLE (-7200 4375);
FORCEPROP 1 LAST HDL_POWER GND
J 1
(-7175 4300);
DISPLAY 0.872340 (-7175 4300);
PAINT GREEN (-7175 4300);
DISPLAY INVISIBLE (-7175 4300);
FORCEPROP 1 LAST PATH I35
J 0
(-7125 4375);
DISPLAY 0.872340 (-7125 4375);
PAINT AQUA (-7125 4375);
DISPLAY INVISIBLE (-7125 4375);
FORCEADD OFFPAGE..2
R 2
(-6825 4350);
FORCEPROP 2 LAST $XR3 210 
J 0
(-7350 4314);
DISPLAY 0.638298 (-7350 4314);
PAINT MONO (-7350 4314);
FORCEPROP 2 LAST $XR2 213 
J 0
(-7230 4314);
DISPLAY 0.638298 (-7230 4314);
PAINT MONO (-7230 4314);
FORCEPROP 2 LAST $XR1 212 
J 0
(-7110 4314);
DISPLAY 0.638298 (-7110 4314);
PAINT MONO (-7110 4314);
FORCEPROP 2 LAST $XR0 211 
J 0
(-7110 4350);
DISPLAY 0.638298 (-7110 4350);
PAINT MONO (-7110 4350);
FORCEPROP 2 LAST CDS_LIB standard
J 0
(-6825 4350);
DISPLAY INVISIBLE (-6825 4350);
FORCEPROP 1 LAST OFFPAGE TRUE
J 2
(-7150 4225);
DISPLAY 0.872340 (-7150 4225);
PAINT GREEN (-7150 4225);
DISPLAY INVISIBLE (-7150 4225);
FORCEPROP 1 LAST COMMENT_BODY TRUE
J 2
(-6780 4255);
DISPLAY 0.872340 (-6780 4255);
PAINT GREEN (-6780 4255);
DISPLAY INVISIBLE (-6780 4255);
FORCEPROP 2 LAST PATH I36
J 0
(-7075 4400);
DISPLAY 0.680851 (-7075 4400);
DISPLAY INVISIBLE (-7075 4400);
FORCEADD Q_RES..1
(-6875 4550);
FORCEPROP 1 LAST LOCATION PR202
J 0
(-6900 4600);
DISPLAY 0.489362 (-6900 4600);
PAINT SKYBLUE (-6900 4600);
FORCEPROP 0 LAST $SEC 1
J 0
(-6875 4625);
DISPLAY 0.680851 (-6875 4625);
PAINT MONO (-6875 4625);
DISPLAY INVISIBLE (-6875 4625);
FORCEPROP 0 LAST CDS_SEC 1
J 0
(-6875 4625);
DISPLAY 1.021277 (-6875 4625);
DISPLAY INVISIBLE (-6875 4625);
FORCEPROP 1 LASTPIN (-6975 4550) $PN 1
J 0
(-6963 4562);
DISPLAY 0.489362 (-6963 4562);
PAINT MONO (-6963 4562);
FORCEPROP 1 LASTPIN (-6775 4550) $PN 2
J 0
(-6813 4562);
DISPLAY 0.489362 (-6813 4562);
PAINT MONO (-6813 4562);
FORCEPROP 1 LAST PACK_TYPE 0402LF
J 0
(-6775 4500);
DISPLAY 0.489362 (-6775 4500);
PAINT SKYBLUE (-6775 4500);
FORCEPROP 1 LAST MATERIAL EMPTY
J 0
(-7175 4450);
DISPLAY 0.489362 (-7175 4450);
PAINT RED (-7175 4450);
FORCEPROP 1 LAST TOLERANCE 1%
J 0
(-6750 4575);
DISPLAY 0.489362 (-6750 4575);
PAINT SKYBLUE (-6750 4575);
FORCEPROP 1 LAST WATTAGE 1/16W
J 0
(-6775 4450);
DISPLAY 0.489362 (-6775 4450);
PAINT SKYBLUE (-6775 4450);
FORCEPROP 1 LAST VALUE 8.87K
J 2
(-7000 4575);
DISPLAY 0.489362 (-7000 4575);
PAINT SKYBLUE (-7000 4575);
FORCEPROP 2 LAST CDS_LIB pure_quanta
J 0
(-6875 4550);
DISPLAY INVISIBLE (-6875 4550);
FORCEPROP 1 LAST PATH I37
J 0
(-6925 4700);
DISPLAY 0.978723 (-6925 4700);
PAINT WHITE (-6925 4700);
DISPLAY INVISIBLE (-6925 4700);
FORCEPROP 1 LAST PART_NUMBER CS28872FB01
J 0
(-7175 4500);
DISPLAY 0.489362 (-7175 4500);
PAINT SKYBLUE (-7175 4500);
DISPLAY INVISIBLE (-7175 4500);
FORCEADD UNIVERSAL_GND..1
(-7200 5000);
FORCEPROP 3 LASTPIN (-7200 5050) SIG_NAME GND\g
J 0
(-7190 5060);
DISPLAY 0.659574 (-7190 5060);
PAINT MONO (-7190 5060);
DISPLAY INVISIBLE (-7190 5060);
FORCEPROP 2 LAST CDS_LIB pure_quanta_power
J 0
(-7200 5000);
DISPLAY INVISIBLE (-7200 5000);
FORCEPROP 1 LAST HDL_POWER GND
J 1
(-7175 4925);
DISPLAY 0.872340 (-7175 4925);
PAINT GREEN (-7175 4925);
DISPLAY INVISIBLE (-7175 4925);
FORCEPROP 1 LAST PATH I38
J 0
(-7125 5000);
DISPLAY 0.872340 (-7125 5000);
PAINT AQUA (-7125 5000);
DISPLAY INVISIBLE (-7125 5000);
FORCEADD Q_CAP..1
(-7200 5200);
FORCEPROP 1 LAST LOCATION PC307
J 0
(-7150 5300);
DISPLAY 0.489362 (-7150 5300);
PAINT SKYBLUE (-7150 5300);
FORCEPROP 0 LAST $SEC 1
J 0
(-7150 5350);
DISPLAY 0.680851 (-7150 5350);
PAINT MONO (-7150 5350);
DISPLAY INVISIBLE (-7150 5350);
FORCEPROP 0 LAST CDS_SEC 1
J 0
(-7150 5350);
DISPLAY 1.021277 (-7150 5350);
DISPLAY INVISIBLE (-7150 5350);
FORCEPROP 1 LASTPIN (-7200 5300) $PN 1
J 0
(-7190 5280);
DISPLAY 0.489362 (-7190 5280);
PAINT MONO (-7190 5280);
FORCEPROP 1 LASTPIN (-7200 5100) $PN 2
J 0
(-7190 5080);
DISPLAY 0.489362 (-7190 5080);
PAINT MONO (-7190 5080);
FORCEPROP 1 LAST MATERIAL X6S
J 0
(-7150 5100);
DISPLAY 0.489362 (-7150 5100);
PAINT SKYBLUE (-7150 5100);
FORCEPROP 1 LAST TOLERANCE 10%
J 0
(-7150 5150);
DISPLAY 0.489362 (-7150 5150);
PAINT SKYBLUE (-7150 5150);
FORCEPROP 1 LAST VALUE 2.2UF
J 0
(-7150 5250);
DISPLAY 0.489362 (-7150 5250);
PAINT SKYBLUE (-7150 5250);
FORCEPROP 1 LAST VOLTAGE 10V
J 0
(-7150 5200);
DISPLAY 0.489362 (-7150 5200);
PAINT SKYBLUE (-7150 5200);
FORCEPROP 1 LAST PACK_TYPE C0402
J 0
(-7150 5000);
DISPLAY 0.489362 (-7150 5000);
PAINT SKYBLUE (-7150 5000);
FORCEPROP 2 LAST CDS_LIB pure_quanta
J 0
(-7200 5200);
DISPLAY INVISIBLE (-7200 5200);
FORCEPROP 1 LAST PATH I39
J 0
(-7150 5350);
DISPLAY 0.978723 (-7150 5350);
PAINT WHITE (-7150 5350);
DISPLAY INVISIBLE (-7150 5350);
FORCEPROP 1 LAST PART_NUMBER CH5222KEB01
J 0
(-7150 5050);
DISPLAY 0.489362 (-7150 5050);
PAINT SKYBLUE (-7150 5050);
DISPLAY INVISIBLE (-7150 5050);
FORCEADD Q_CAP..1
(-7475 1675);
FORCEPROP 1 LAST LOCATION PC124_6
J 0
(-7425 1775);
DISPLAY 0.489362 (-7425 1775);
PAINT SKYBLUE (-7425 1775);
FORCEPROP 0 LAST $SEC 1
J 0
(-7425 1800);
DISPLAY 0.680851 (-7425 1800);
PAINT MONO (-7425 1800);
DISPLAY INVISIBLE (-7425 1800);
FORCEPROP 0 LAST CDS_SEC 1
J 0
(-7425 1800);
DISPLAY 1.021277 (-7425 1800);
DISPLAY INVISIBLE (-7425 1800);
FORCEPROP 1 LASTPIN (-7475 1775) $PN 1
J 0
(-7465 1755);
DISPLAY 0.489362 (-7465 1755);
PAINT MONO (-7465 1755);
FORCEPROP 1 LASTPIN (-7475 1575) $PN 2
J 0
(-7465 1555);
DISPLAY 0.489362 (-7465 1555);
PAINT MONO (-7465 1555);
FORCEPROP 1 LAST MATERIAL X7R
J 0
(-7425 1575);
DISPLAY 0.489362 (-7425 1575);
PAINT SKYBLUE (-7425 1575);
FORCEPROP 1 LAST TOLERANCE 10%
J 0
(-7425 1625);
DISPLAY 0.489362 (-7425 1625);
PAINT SKYBLUE (-7425 1625);
FORCEPROP 1 LAST VALUE 0.1UF
J 0
(-7425 1725);
DISPLAY 0.489362 (-7425 1725);
PAINT SKYBLUE (-7425 1725);
FORCEPROP 1 LAST VOLTAGE 25V
J 0
(-7425 1675);
DISPLAY 0.489362 (-7425 1675);
PAINT SKYBLUE (-7425 1675);
FORCEPROP 1 LAST PACK_TYPE 0402
J 0
(-7425 1475);
DISPLAY 0.489362 (-7425 1475);
PAINT SKYBLUE (-7425 1475);
FORCEPROP 2 LAST CDS_LIB pure_quanta
J 0
(-7475 1675);
DISPLAY INVISIBLE (-7475 1675);
FORCEPROP 1 LAST PATH I4
J 0
(-7425 1825);
DISPLAY 0.978723 (-7425 1825);
PAINT WHITE (-7425 1825);
DISPLAY INVISIBLE (-7425 1825);
FORCEPROP 1 LAST PART_NUMBER CH4104K1B00
J 0
(-7425 1525);
DISPLAY 0.489362 (-7425 1525);
PAINT SKYBLUE (-7425 1525);
DISPLAY INVISIBLE (-7425 1525);
FORCEADD OFFPAGE..2
R 2
(-6850 4850);
FORCEPROP 2 LAST $XR0 210 
J 0
(-7135 4850);
DISPLAY 0.638298 (-7135 4850);
PAINT MONO (-7135 4850);
FORCEPROP 2 LAST CDS_LIB standard
J 2
(-6850 4850);
DISPLAY INVISIBLE (-6850 4850);
FORCEPROP 1 LAST OFFPAGE TRUE
J 2
(-7175 4725);
DISPLAY 0.872340 (-7175 4725);
PAINT GREEN (-7175 4725);
DISPLAY INVISIBLE (-7175 4725);
FORCEPROP 1 LAST COMMENT_BODY TRUE
J 2
(-6805 4755);
DISPLAY 0.872340 (-6805 4755);
PAINT GREEN (-6805 4755);
DISPLAY INVISIBLE (-6805 4755);
FORCEPROP 2 LAST PATH I40
J 0
(-7100 4900);
DISPLAY 0.680851 (-7100 4900);
DISPLAY INVISIBLE (-7100 4900);
FORCEADD Q_RES..2
(-7200 5750);
FORCEPROP 1 LAST LOCATION PR201
J 0
(-7155 5875);
DISPLAY 0.489362 (-7155 5875);
PAINT SKYBLUE (-7155 5875);
FORCEPROP 0 LAST $SEC 1
J 0
(-7150 5925);
DISPLAY 0.680851 (-7150 5925);
PAINT MONO (-7150 5925);
DISPLAY INVISIBLE (-7150 5925);
FORCEPROP 0 LAST CDS_SEC 1
J 0
(-7150 5925);
DISPLAY 1.021277 (-7150 5925);
DISPLAY INVISIBLE (-7150 5925);
FORCEPROP 1 LASTPIN (-7200 5850) $PN 1
J 0
(-7195 5812);
DISPLAY 0.489362 (-7195 5812);
PAINT MONO (-7195 5812);
FORCEPROP 1 LASTPIN (-7200 5650) $PN 2
J 0
(-7195 5660);
DISPLAY 0.489362 (-7195 5660);
PAINT MONO (-7195 5660);
FORCEPROP 1 LAST PACK_TYPE 0402LF
J 0
(-7150 5575);
DISPLAY 0.489362 (-7150 5575);
PAINT SKYBLUE (-7150 5575);
FORCEPROP 1 LAST VALUE 2.2
J 0
(-7150 5825);
DISPLAY 0.489362 (-7150 5825);
PAINT SKYBLUE (-7150 5825);
FORCEPROP 1 LAST TOLERANCE 1%
J 0
(-7150 5775);
DISPLAY 0.489362 (-7150 5775);
PAINT SKYBLUE (-7150 5775);
FORCEPROP 1 LAST MATERIAL CHIP
J 0
(-7150 5675);
DISPLAY 0.489362 (-7150 5675);
PAINT SKYBLUE (-7150 5675);
FORCEPROP 1 LAST WATTAGE 1/16W
J 0
(-7150 5725);
DISPLAY 0.489362 (-7150 5725);
PAINT SKYBLUE (-7150 5725);
FORCEPROP 2 LAST CDS_LIB pure_quanta
J 0
(-7200 5750);
DISPLAY INVISIBLE (-7200 5750);
FORCEPROP 1 LAST PATH I41
J 0
(-7150 5925);
DISPLAY 0.978723 (-7150 5925);
PAINT WHITE (-7150 5925);
DISPLAY INVISIBLE (-7150 5925);
FORCEPROP 1 LAST PART_NUMBER CS-2202FB01
J 0
(-7150 5625);
DISPLAY 0.489362 (-7150 5625);
PAINT SKYBLUE (-7150 5625);
DISPLAY INVISIBLE (-7150 5625);
FORCEADD UNIVERSAL_GND..1
(-6850 5500);
FORCEPROP 3 LASTPIN (-6850 5550) SIG_NAME GND\g
J 0
(-6840 5560);
DISPLAY 0.659574 (-6840 5560);
PAINT MONO (-6840 5560);
DISPLAY INVISIBLE (-6840 5560);
FORCEPROP 2 LAST CDS_LIB pure_quanta_power
J 0
(-6850 5500);
DISPLAY INVISIBLE (-6850 5500);
FORCEPROP 1 LAST HDL_POWER GND
J 1
(-6825 5425);
DISPLAY 0.872340 (-6825 5425);
PAINT GREEN (-6825 5425);
DISPLAY INVISIBLE (-6825 5425);
FORCEPROP 1 LAST PATH I42
J 0
(-6775 5500);
DISPLAY 0.872340 (-6775 5500);
PAINT AQUA (-6775 5500);
DISPLAY INVISIBLE (-6775 5500);
FORCEADD Q_CAP..1
(-6850 5775);
FORCEPROP 1 LAST LOCATION PC308_C0P1_5
J 0
(-6800 5875);
DISPLAY 0.489362 (-6800 5875);
PAINT SKYBLUE (-6800 5875);
FORCEPROP 0 LAST $SEC 1
J 0
(-6800 5925);
DISPLAY 0.680851 (-6800 5925);
PAINT MONO (-6800 5925);
DISPLAY INVISIBLE (-6800 5925);
FORCEPROP 0 LAST CDS_SEC 1
J 0
(-6800 5925);
DISPLAY 1.021277 (-6800 5925);
DISPLAY INVISIBLE (-6800 5925);
FORCEPROP 1 LASTPIN (-6850 5875) $PN 1
J 0
(-6840 5855);
DISPLAY 0.489362 (-6840 5855);
PAINT MONO (-6840 5855);
FORCEPROP 1 LASTPIN (-6850 5675) $PN 2
J 0
(-6840 5655);
DISPLAY 0.489362 (-6840 5655);
PAINT MONO (-6840 5655);
FORCEPROP 1 LAST MATERIAL X6S
J 0
(-6800 5675);
DISPLAY 0.489362 (-6800 5675);
PAINT SKYBLUE (-6800 5675);
FORCEPROP 1 LAST TOLERANCE 10%
J 0
(-6800 5725);
DISPLAY 0.489362 (-6800 5725);
PAINT SKYBLUE (-6800 5725);
FORCEPROP 1 LAST VALUE 2.2UF
J 0
(-6800 5825);
DISPLAY 0.489362 (-6800 5825);
PAINT SKYBLUE (-6800 5825);
FORCEPROP 1 LAST VOLTAGE 10V
J 0
(-6800 5775);
DISPLAY 0.489362 (-6800 5775);
PAINT SKYBLUE (-6800 5775);
FORCEPROP 1 LAST PACK_TYPE C0402
J 0
(-6800 5575);
DISPLAY 0.489362 (-6800 5575);
PAINT SKYBLUE (-6800 5575);
FORCEPROP 2 LAST CDS_LIB pure_quanta
J 0
(-6850 5775);
DISPLAY INVISIBLE (-6850 5775);
FORCEPROP 1 LAST PATH I43
J 0
(-6800 5925);
DISPLAY 0.978723 (-6800 5925);
PAINT WHITE (-6800 5925);
DISPLAY INVISIBLE (-6800 5925);
FORCEPROP 1 LAST PART_NUMBER CH5222KEB01
J 0
(-6800 5625);
DISPLAY 0.489362 (-6800 5625);
PAINT SKYBLUE (-6800 5625);
DISPLAY INVISIBLE (-6800 5625);
FORCEADD VCC_CORE..1
(-7200 6150);
FORCEPROP 3 LASTPIN (-7200 6100) SIG_NAME PVDDCR_CPU0_P1_PVCC\g
J 0
(-7190 6110);
DISPLAY 0.659574 (-7190 6110);
PAINT MONO (-7190 6110);
DISPLAY INVISIBLE (-7190 6110);
FORCEPROP 1 LAST HDL_POWER PVDDCR_CPU0_P1_PVCC
J 1
(-7200 6200);
DISPLAY 0.489362 (-7200 6200);
PAINT GREEN (-7200 6200);
FORCEPROP 2 LAST CDS_LIB pure_quanta_power
J 0
(-7200 6150);
DISPLAY INVISIBLE (-7200 6150);
FORCEPROP 1 LAST PATH I44
J 0
(-7150 6175);
DISPLAY 0.872340 (-7150 6175);
PAINT AQUA (-7150 6175);
DISPLAY INVISIBLE (-7150 6175);
FORCEADD Q_CAP..1
(-4950 5725);
FORCEPROP 1 LAST LOCATION PC309_5
J 0
(-4900 5825);
DISPLAY 0.489362 (-4900 5825);
PAINT SKYBLUE (-4900 5825);
FORCEPROP 0 LAST $SEC 1
J 0
(-4900 5875);
DISPLAY 0.680851 (-4900 5875);
PAINT MONO (-4900 5875);
DISPLAY INVISIBLE (-4900 5875);
FORCEPROP 0 LAST CDS_SEC 1
J 0
(-4900 5875);
DISPLAY 1.021277 (-4900 5875);
DISPLAY INVISIBLE (-4900 5875);
FORCEPROP 1 LASTPIN (-4950 5825) $PN 1
J 0
(-4940 5805);
DISPLAY 0.489362 (-4940 5805);
PAINT MONO (-4940 5805);
FORCEPROP 1 LASTPIN (-4950 5625) $PN 2
J 0
(-4940 5605);
DISPLAY 0.489362 (-4940 5605);
PAINT MONO (-4940 5605);
FORCEPROP 1 LAST MATERIAL X7R
J 0
(-4900 5625);
DISPLAY 0.489362 (-4900 5625);
PAINT SKYBLUE (-4900 5625);
FORCEPROP 1 LAST TOLERANCE 10%
J 0
(-4900 5675);
DISPLAY 0.489362 (-4900 5675);
PAINT SKYBLUE (-4900 5675);
FORCEPROP 1 LAST VALUE 0.1UF
J 0
(-4900 5775);
DISPLAY 0.489362 (-4900 5775);
PAINT SKYBLUE (-4900 5775);
FORCEPROP 1 LAST VOLTAGE 25V
J 0
(-4900 5725);
DISPLAY 0.489362 (-4900 5725);
PAINT SKYBLUE (-4900 5725);
FORCEPROP 1 LAST PACK_TYPE 0402
J 0
(-4900 5525);
DISPLAY 0.489362 (-4900 5525);
PAINT SKYBLUE (-4900 5525);
FORCEPROP 2 LAST CDS_LIB pure_quanta
J 0
(-4950 5725);
DISPLAY INVISIBLE (-4950 5725);
FORCEPROP 1 LAST PATH I45
J 0
(-4900 5875);
DISPLAY 0.978723 (-4900 5875);
PAINT WHITE (-4900 5875);
DISPLAY INVISIBLE (-4900 5875);
FORCEPROP 1 LAST PART_NUMBER CH4104K1B00
J 0
(-4900 5575);
DISPLAY 0.489362 (-4900 5575);
PAINT SKYBLUE (-4900 5575);
DISPLAY INVISIBLE (-4900 5575);
FORCEADD Q_CAP..1
(-4275 4650);
FORCEPROP 1 LAST LOCATION PC318
J 0
(-4225 4750);
DISPLAY 0.489362 (-4225 4750);
PAINT SKYBLUE (-4225 4750);
FORCEPROP 0 LAST $SEC 1
J 0
(-4225 4800);
DISPLAY 0.680851 (-4225 4800);
PAINT MONO (-4225 4800);
DISPLAY INVISIBLE (-4225 4800);
FORCEPROP 0 LAST CDS_SEC 1
J 0
(-4225 4800);
DISPLAY 1.021277 (-4225 4800);
DISPLAY INVISIBLE (-4225 4800);
FORCEPROP 1 LASTPIN (-4275 4750) $PN 1
J 0
(-4265 4730);
DISPLAY 0.489362 (-4265 4730);
PAINT MONO (-4265 4730);
FORCEPROP 1 LASTPIN (-4275 4550) $PN 2
J 0
(-4265 4530);
DISPLAY 0.489362 (-4265 4530);
PAINT MONO (-4265 4530);
FORCEPROP 1 LAST MATERIAL EMPTY
J 0
(-4225 4550);
DISPLAY 0.489362 (-4225 4550);
PAINT RED (-4225 4550);
FORCEPROP 1 LAST TOLERANCE 10%
J 0
(-4225 4600);
DISPLAY 0.489362 (-4225 4600);
PAINT SKYBLUE (-4225 4600);
FORCEPROP 1 LAST VOLTAGE 50V
J 0
(-4225 4650);
DISPLAY 0.489362 (-4225 4650);
PAINT SKYBLUE (-4225 4650);
FORCEPROP 1 LAST VALUE 560PF
J 0
(-4225 4700);
DISPLAY 0.489362 (-4225 4700);
PAINT SKYBLUE (-4225 4700);
FORCEPROP 1 LAST PACK_TYPE C0402
J 0
(-4225 4450);
DISPLAY 0.489362 (-4225 4450);
PAINT SKYBLUE (-4225 4450);
FORCEPROP 2 LAST CDS_LIB pure_quanta
J 0
(-4275 4650);
DISPLAY INVISIBLE (-4275 4650);
FORCEPROP 1 LAST PATH I46
J 0
(-4225 4800);
DISPLAY 0.978723 (-4225 4800);
PAINT WHITE (-4225 4800);
DISPLAY INVISIBLE (-4225 4800);
FORCEPROP 1 LAST PART_NUMBER CH1566K1B09
J 0
(-4225 4500);
DISPLAY 0.489362 (-4225 4500);
PAINT SKYBLUE (-4225 4500);
DISPLAY INVISIBLE (-4225 4500);
FORCEADD Q_RES..1
(-4300 5200);
FORCEPROP 1 LAST LOCATION PR203
J 0
(-4325 5250);
DISPLAY 0.489362 (-4325 5250);
PAINT SKYBLUE (-4325 5250);
FORCEPROP 0 LAST $SEC 1
J 0
(-4275 5275);
DISPLAY 0.680851 (-4275 5275);
PAINT MONO (-4275 5275);
DISPLAY INVISIBLE (-4275 5275);
FORCEPROP 0 LAST CDS_SEC 1
J 0
(-4275 5275);
DISPLAY 1.021277 (-4275 5275);
DISPLAY INVISIBLE (-4275 5275);
FORCEPROP 1 LASTPIN (-4400 5200) $PN 1
J 0
(-4388 5212);
DISPLAY 0.489362 (-4388 5212);
PAINT MONO (-4388 5212);
FORCEPROP 1 LASTPIN (-4200 5200) $PN 2
J 0
(-4238 5212);
DISPLAY 0.489362 (-4238 5212);
PAINT MONO (-4238 5212);
FORCEPROP 1 LAST VALUE 5.6
J 2
(-4400 5225);
DISPLAY 0.489362 (-4400 5225);
PAINT SKYBLUE (-4400 5225);
FORCEPROP 1 LAST PACK_TYPE 0402LF
J 0
(-4200 5100);
DISPLAY 0.489362 (-4200 5100);
PAINT SKYBLUE (-4200 5100);
FORCEPROP 1 LAST WATTAGE 1/16W
J 0
(-4200 5150);
DISPLAY 0.489362 (-4200 5150);
PAINT SKYBLUE (-4200 5150);
FORCEPROP 1 LAST TOLERANCE 1%
J 0
(-4200 5225);
DISPLAY 0.489362 (-4200 5225);
PAINT SKYBLUE (-4200 5225);
FORCEPROP 1 LAST MATERIAL CHIP
J 0
(-4550 5100);
DISPLAY 0.489362 (-4550 5100);
PAINT SKYBLUE (-4550 5100);
FORCEPROP 2 LAST CDS_LIB pure_quanta
J 0
(-4300 5200);
DISPLAY INVISIBLE (-4300 5200);
FORCEPROP 1 LAST PATH I47
J 0
(-4350 5350);
DISPLAY 0.978723 (-4350 5350);
PAINT WHITE (-4350 5350);
DISPLAY INVISIBLE (-4350 5350);
FORCEPROP 1 LAST PART_NUMBER CS-5602FB01
J 0
(-4550 5150);
DISPLAY 0.489362 (-4550 5150);
PAINT SKYBLUE (-4550 5150);
DISPLAY INVISIBLE (-4550 5150);
FORCEADD Q_CAP..1
(-4575 5725);
FORCEPROP 1 LAST LOCATION PC310_5
J 0
(-4525 5825);
DISPLAY 0.489362 (-4525 5825);
PAINT SKYBLUE (-4525 5825);
FORCEPROP 0 LAST $SEC 1
J 0
(-4525 5850);
DISPLAY 0.680851 (-4525 5850);
PAINT MONO (-4525 5850);
DISPLAY INVISIBLE (-4525 5850);
FORCEPROP 0 LAST CDS_SEC 1
J 0
(-4525 5850);
DISPLAY 1.021277 (-4525 5850);
DISPLAY INVISIBLE (-4525 5850);
FORCEPROP 1 LASTPIN (-4575 5825) $PN 1
J 0
(-4565 5805);
DISPLAY 0.489362 (-4565 5805);
PAINT MONO (-4565 5805);
FORCEPROP 1 LASTPIN (-4575 5625) $PN 2
J 0
(-4565 5605);
DISPLAY 0.489362 (-4565 5605);
PAINT MONO (-4565 5605);
FORCEPROP 1 LAST PACK_TYPE C0402
J 0
(-4525 5525);
DISPLAY 0.489362 (-4525 5525);
PAINT SKYBLUE (-4525 5525);
FORCEPROP 1 LAST MATERIAL X6S
J 0
(-4525 5625);
DISPLAY 0.489362 (-4525 5625);
PAINT SKYBLUE (-4525 5625);
FORCEPROP 1 LAST TOLERANCE 10%
J 0
(-4525 5675);
DISPLAY 0.489362 (-4525 5675);
PAINT SKYBLUE (-4525 5675);
FORCEPROP 1 LAST VALUE 1UF
J 0
(-4525 5775);
DISPLAY 0.489362 (-4525 5775);
PAINT SKYBLUE (-4525 5775);
FORCEPROP 1 LAST VOLTAGE 25V
J 0
(-4525 5725);
DISPLAY 0.489362 (-4525 5725);
PAINT SKYBLUE (-4525 5725);
FORCEPROP 2 LAST CDS_LIB pure_quanta
J 0
(-4575 5725);
DISPLAY INVISIBLE (-4575 5725);
FORCEPROP 1 LAST PATH I48
J 0
(-4525 5875);
DISPLAY 0.978723 (-4525 5875);
PAINT WHITE (-4525 5875);
DISPLAY INVISIBLE (-4525 5875);
FORCEPROP 1 LAST PART_NUMBER CH5104KEB02
J 0
(-4525 5575);
DISPLAY 0.489362 (-4525 5575);
PAINT SKYBLUE (-4525 5575);
DISPLAY INVISIBLE (-4525 5575);
FORCEADD Q_CAP..1
(-4250 5725);
FORCEPROP 1 LAST LOCATION PC311_5
J 0
(-4200 5825);
DISPLAY 0.489362 (-4200 5825);
PAINT SKYBLUE (-4200 5825);
FORCEPROP 0 LAST $SEC 1
J 0
(-4200 5850);
DISPLAY 0.680851 (-4200 5850);
PAINT MONO (-4200 5850);
DISPLAY INVISIBLE (-4200 5850);
FORCEPROP 0 LAST CDS_SEC 1
J 0
(-4200 5850);
DISPLAY 1.021277 (-4200 5850);
DISPLAY INVISIBLE (-4200 5850);
FORCEPROP 1 LASTPIN (-4250 5825) $PN 1
J 0
(-4240 5805);
DISPLAY 0.489362 (-4240 5805);
PAINT MONO (-4240 5805);
FORCEPROP 1 LASTPIN (-4250 5625) $PN 2
J 0
(-4240 5605);
DISPLAY 0.489362 (-4240 5605);
PAINT MONO (-4240 5605);
FORCEPROP 1 LAST MATERIAL X6S
J 0
(-4200 5625);
DISPLAY 0.489362 (-4200 5625);
PAINT SKYBLUE (-4200 5625);
FORCEPROP 1 LAST PACK_TYPE C0805
J 0
(-4200 5525);
DISPLAY 0.489362 (-4200 5525);
PAINT SKYBLUE (-4200 5525);
FORCEPROP 1 LAST VALUE 22UF
J 0
(-4200 5775);
DISPLAY 0.489362 (-4200 5775);
PAINT SKYBLUE (-4200 5775);
FORCEPROP 1 LAST VOLTAGE 16V
J 0
(-4200 5725);
DISPLAY 0.489362 (-4200 5725);
PAINT SKYBLUE (-4200 5725);
FORCEPROP 1 LAST TOLERANCE 20%
J 0
(-4200 5675);
DISPLAY 0.489362 (-4200 5675);
PAINT SKYBLUE (-4200 5675);
FORCEPROP 2 LAST CDS_LIB pure_quanta
J 0
(-4250 5725);
DISPLAY INVISIBLE (-4250 5725);
FORCEPROP 1 LAST PATH I49
J 0
(-4200 5875);
DISPLAY 0.978723 (-4200 5875);
PAINT WHITE (-4200 5875);
DISPLAY INVISIBLE (-4200 5875);
FORCEPROP 1 LAST PART_NUMBER CH6223MEA01
J 0
(-4200 5575);
DISPLAY 0.489362 (-4200 5575);
PAINT SKYBLUE (-4200 5575);
DISPLAY INVISIBLE (-4200 5575);
FORCEADD UNIVERSAL_GND..1
(-7150 1475);
FORCEPROP 3 LASTPIN (-7150 1525) SIG_NAME GND\g
J 0
(-7140 1535);
DISPLAY 0.659574 (-7140 1535);
PAINT MONO (-7140 1535);
DISPLAY INVISIBLE (-7140 1535);
FORCEPROP 2 LAST CDS_LIB pure_quanta_power
J 0
(-7150 1475);
DISPLAY INVISIBLE (-7150 1475);
FORCEPROP 1 LAST HDL_POWER GND
J 1
(-7125 1400);
DISPLAY 0.872340 (-7125 1400);
PAINT GREEN (-7125 1400);
DISPLAY INVISIBLE (-7125 1400);
FORCEPROP 1 LAST PATH I5
J 0
(-7075 1475);
DISPLAY 0.872340 (-7075 1475);
PAINT AQUA (-7075 1475);
DISPLAY INVISIBLE (-7075 1475);
FORCEADD Q_CAP..1
(-3925 5725);
FORCEPROP 1 LAST LOCATION PC312_5
J 0
(-3875 5825);
DISPLAY 0.489362 (-3875 5825);
PAINT SKYBLUE (-3875 5825);
FORCEPROP 0 LAST $SEC 1
J 0
(-3875 5850);
DISPLAY 0.680851 (-3875 5850);
PAINT MONO (-3875 5850);
DISPLAY INVISIBLE (-3875 5850);
FORCEPROP 0 LAST CDS_SEC 1
J 0
(-3875 5850);
DISPLAY 1.021277 (-3875 5850);
DISPLAY INVISIBLE (-3875 5850);
FORCEPROP 1 LASTPIN (-3925 5825) $PN 1
J 0
(-3915 5805);
DISPLAY 0.489362 (-3915 5805);
PAINT MONO (-3915 5805);
FORCEPROP 1 LASTPIN (-3925 5625) $PN 2
J 0
(-3915 5605);
DISPLAY 0.489362 (-3915 5605);
PAINT MONO (-3915 5605);
FORCEPROP 1 LAST MATERIAL X6S
J 0
(-3875 5625);
DISPLAY 0.489362 (-3875 5625);
PAINT SKYBLUE (-3875 5625);
FORCEPROP 1 LAST VALUE 22UF
J 0
(-3875 5775);
DISPLAY 0.489362 (-3875 5775);
PAINT SKYBLUE (-3875 5775);
FORCEPROP 1 LAST VOLTAGE 16V
J 0
(-3875 5725);
DISPLAY 0.489362 (-3875 5725);
PAINT SKYBLUE (-3875 5725);
FORCEPROP 1 LAST TOLERANCE 20%
J 0
(-3875 5675);
DISPLAY 0.489362 (-3875 5675);
PAINT SKYBLUE (-3875 5675);
FORCEPROP 1 LAST PACK_TYPE C0805
J 0
(-3875 5525);
DISPLAY 0.489362 (-3875 5525);
PAINT SKYBLUE (-3875 5525);
FORCEPROP 2 LAST CDS_LIB pure_quanta
J 0
(-3925 5725);
DISPLAY INVISIBLE (-3925 5725);
FORCEPROP 1 LAST PATH I50
J 0
(-3875 5875);
DISPLAY 0.978723 (-3875 5875);
PAINT WHITE (-3875 5875);
DISPLAY INVISIBLE (-3875 5875);
FORCEPROP 1 LAST PART_NUMBER CH6223MEA01
J 0
(-3875 5575);
DISPLAY 0.489362 (-3875 5575);
PAINT SKYBLUE (-3875 5575);
DISPLAY INVISIBLE (-3875 5575);
FORCEADD Q_INDUCTOR..1
(-3400 1725);
FORCEPROP 1 LAST LOCATION PL27
J 0
(-3550 1875);
DISPLAY 0.489362 (-3550 1875);
PAINT SKYBLUE (-3550 1875);
FORCEPROP 0 LAST $SEC 1
J 0
(-3550 1900);
DISPLAY 0.680851 (-3550 1900);
PAINT MONO (-3550 1900);
DISPLAY INVISIBLE (-3550 1900);
FORCEPROP 0 LAST CDS_SEC 1
J 0
(-3550 1900);
DISPLAY 0.680851 (-3550 1900);
DISPLAY INVISIBLE (-3550 1900);
FORCEPROP 0 LASTPIN (-3500 1700) $PN 1
J 2
(-3510 1710);
DISPLAY 0.489362 (-3510 1710);
PAINT MONO (-3510 1710);
FORCEPROP 0 LASTPIN (-3300 1700) $PN 2
J 0
(-3290 1710);
DISPLAY 0.489362 (-3290 1710);
PAINT MONO (-3290 1710);
FORCEPROP 2 LASTPIN (-3300 1700) SIG_NAME IND_CPU0_P1_CPL0
J 0
(-3285 1710);
DISPLAY 0.489362 (-3285 1710);
FORCEPROP 2 LASTPROP $XRERR UNIQUE?
J 0
(-3525 1710);
DISPLAY 0.638298 (-3525 1710);
PAINT MONO (-3525 1710);
DISPLAY INVISIBLE (-3525 1710);
FORCEPROP 2 LAST VALUE 120NH/69A
J 0
(-3550 1850);
DISPLAY 0.489362 (-3550 1850);
PAINT SKYBLUE (-3550 1850);
FORCEPROP 2 LAST PACK_TYPE SMLF
J 0
(-3550 1825);
DISPLAY 0.489362 (-3550 1825);
PAINT SKYBLUE (-3550 1825);
FORCEPROP 1 LAST MATERIAL IND
J 0
(-3550 1775);
DISPLAY 0.489362 (-3550 1775);
PAINT SKYBLUE (-3550 1775);
FORCEPROP 2 LAST CDS_LIB pure_quanta
J 0
(-3400 1725);
DISPLAY INVISIBLE (-3400 1725);
FORCEPROP 1 LAST NEEDS_NO_SIZE TRUE
J 0
(-3400 1725);
DISPLAY 0.468085 (-3400 1725);
PAINT GREEN (-3400 1725);
DISPLAY INVISIBLE (-3400 1725);
FORCEPROP 1 LAST PATH I51
J 0
(-3325 1780);
DISPLAY 0.723404 (-3325 1780);
PAINT GREEN (-3325 1780);
DISPLAY INVISIBLE (-3325 1780);
FORCEPROP 1 LAST PART_NUMBER CV+12^0EZ03
J 0
(-3550 1800);
DISPLAY 0.489362 (-3550 1800);
PAINT SKYBLUE (-3550 1800);
DISPLAY INVISIBLE (-3550 1800);
FORCEADD Q_CAP..1
(-3275 2175);
FORCEPROP 1 LAST LOCATION PC133
J 0
(-3225 2300);
DISPLAY 0.489362 (-3225 2300);
PAINT SKYBLUE (-3225 2300);
FORCEPROP 0 LAST $SEC 1
J 0
(-3225 2325);
DISPLAY 0.680851 (-3225 2325);
PAINT MONO (-3225 2325);
DISPLAY INVISIBLE (-3225 2325);
FORCEPROP 0 LAST CDS_SEC 1
J 0
(-3225 2325);
DISPLAY 1.021277 (-3225 2325);
DISPLAY INVISIBLE (-3225 2325);
FORCEPROP 1 LASTPIN (-3275 2275) $PN 1
J 0
(-3265 2255);
DISPLAY 0.489362 (-3265 2255);
PAINT MONO (-3265 2255);
FORCEPROP 1 LASTPIN (-3275 2075) $PN 2
J 0
(-3265 2055);
DISPLAY 0.489362 (-3265 2055);
PAINT MONO (-3265 2055);
FORCEPROP 1 LAST MATERIAL X7R
J 0
(-3225 2100);
DISPLAY 0.489362 (-3225 2100);
PAINT SKYBLUE (-3225 2100);
FORCEPROP 1 LAST TOLERANCE 10%
J 0
(-3225 2150);
DISPLAY 0.489362 (-3225 2150);
PAINT SKYBLUE (-3225 2150);
FORCEPROP 1 LAST VALUE 0.22UF
J 0
(-3225 2250);
DISPLAY 0.489362 (-3225 2250);
PAINT SKYBLUE (-3225 2250);
FORCEPROP 1 LAST VOLTAGE 16V
J 0
(-3225 2200);
DISPLAY 0.489362 (-3225 2200);
PAINT SKYBLUE (-3225 2200);
FORCEPROP 1 LAST PACK_TYPE 0402
J 0
(-3225 2000);
DISPLAY 0.489362 (-3225 2000);
PAINT SKYBLUE (-3225 2000);
FORCEPROP 2 LAST CDS_LIB pure_quanta
J 0
(-3275 2175);
DISPLAY INVISIBLE (-3275 2175);
FORCEPROP 1 LAST PATH I52
J 0
(-3225 2325);
DISPLAY 0.978723 (-3225 2325);
PAINT WHITE (-3225 2325);
DISPLAY INVISIBLE (-3225 2325);
FORCEPROP 1 LAST PART_NUMBER CH4223K1B00
J 0
(-3225 2050);
DISPLAY 0.489362 (-3225 2050);
PAINT SKYBLUE (-3225 2050);
DISPLAY INVISIBLE (-3225 2050);
FORCEADD Q_INDUCTOR4P_14..1
(-2425 1825);
FORCEPROP 1 LAST LOCATION PL8
J 0
(-2650 2080);
DISPLAY 0.489362 (-2650 2080);
PAINT SKYBLUE (-2650 2080);
FORCEPROP 0 LAST $SEC 1
J 0
(-2650 2225);
DISPLAY 0.680851 (-2650 2225);
PAINT MONO (-2650 2225);
DISPLAY INVISIBLE (-2650 2225);
FORCEPROP 0 LAST CDS_SEC 1
J 0
(-2650 2225);
DISPLAY 1.021277 (-2650 2225);
DISPLAY INVISIBLE (-2650 2225);
FORCEPROP 0 LASTPIN (-2825 1950) $PN 1
J 2
(-2835 1960);
DISPLAY 0.489362 (-2835 1960);
PAINT MONO (-2835 1960);
FORCEPROP 0 LASTPIN (-2825 1700) $PN 2
J 2
(-2835 1710);
DISPLAY 0.489362 (-2835 1710);
PAINT MONO (-2835 1710);
FORCEPROP 0 LASTPIN (-2025 1700) $PN 3
J 0
(-2015 1710);
DISPLAY 0.489362 (-2015 1710);
PAINT MONO (-2015 1710);
FORCEPROP 0 LASTPIN (-2025 1950) $PN 4
J 0
(-2015 1960);
DISPLAY 0.489362 (-2015 1960);
PAINT MONO (-2015 1960);
FORCEPROP 2 LAST PART_TYPE SMLF
J 0
(-2650 2175);
DISPLAY 1.021277 (-2650 2175);
FORCEPROP 1 LAST MATERIAL IND
J 0
(-2650 2035);
DISPLAY 0.489362 (-2650 2035);
PAINT SKYBLUE (-2650 2035);
FORCEPROP 2 LAST VALUE 150NH
J 0
(-2650 2125);
DISPLAY 0.489362 (-2650 2125);
PAINT SKYBLUE (-2650 2125);
FORCEPROP 1 LAST NEEDS_NO_SIZE TRUE
J 0
(-2425 1825);
DISPLAY 0.468085 (-2425 1825);
PAINT GREEN (-2425 1825);
DISPLAY INVISIBLE (-2425 1825);
FORCEPROP 2 LAST CDS_LIB pure_quanta
J 0
(-2425 1825);
DISPLAY INVISIBLE (-2425 1825);
FORCEPROP 1 LAST PATH I53
J 0
(-2225 1980);
DISPLAY 0.723404 (-2225 1980);
PAINT GREEN (-2225 1980);
DISPLAY INVISIBLE (-2225 1980);
FORCEPROP 1 LAST PART_NUMBER CV+15^0TZ04
J 0
(-2650 1985);
DISPLAY 0.489362 (-2650 1985);
PAINT SKYBLUE (-2650 1985);
DISPLAY INVISIBLE (-2650 1985);
FORCEADD UNIVERSAL_GND..1
(-3575 2475);
FORCEPROP 3 LASTPIN (-3575 2525) SIG_NAME GND\g
J 0
(-3565 2535);
DISPLAY 0.659574 (-3565 2535);
PAINT MONO (-3565 2535);
DISPLAY INVISIBLE (-3565 2535);
FORCEPROP 2 LAST CDS_LIB pure_quanta_power
J 0
(-3575 2475);
DISPLAY INVISIBLE (-3575 2475);
FORCEPROP 1 LAST HDL_POWER GND
J 1
(-3550 2400);
DISPLAY 0.872340 (-3550 2400);
PAINT GREEN (-3550 2400);
DISPLAY INVISIBLE (-3550 2400);
FORCEPROP 1 LAST PATH I54
J 0
(-3500 2475);
DISPLAY 0.872340 (-3500 2475);
PAINT AQUA (-3500 2475);
DISPLAY INVISIBLE (-3500 2475);
FORCEADD Q_CAP..1
(-3575 2825);
FORCEPROP 1 LAST LOCATION PC132_6
J 0
(-3525 2925);
DISPLAY 0.489362 (-3525 2925);
PAINT SKYBLUE (-3525 2925);
FORCEPROP 0 LAST $SEC 1
J 0
(-3525 2950);
DISPLAY 0.680851 (-3525 2950);
PAINT MONO (-3525 2950);
DISPLAY INVISIBLE (-3525 2950);
FORCEPROP 0 LAST CDS_SEC 1
J 0
(-3525 2950);
DISPLAY 1.021277 (-3525 2950);
DISPLAY INVISIBLE (-3525 2950);
FORCEPROP 1 LASTPIN (-3575 2925) $PN 1
J 0
(-3565 2905);
DISPLAY 0.489362 (-3565 2905);
PAINT MONO (-3565 2905);
FORCEPROP 1 LASTPIN (-3575 2725) $PN 2
J 0
(-3565 2705);
DISPLAY 0.489362 (-3565 2705);
PAINT MONO (-3565 2705);
FORCEPROP 1 LAST PACK_TYPE C0805
J 0
(-3525 2625);
DISPLAY 0.489362 (-3525 2625);
PAINT SKYBLUE (-3525 2625);
FORCEPROP 1 LAST MATERIAL X6S
J 0
(-3525 2725);
DISPLAY 0.489362 (-3525 2725);
PAINT SKYBLUE (-3525 2725);
FORCEPROP 1 LAST VALUE 22UF
J 0
(-3525 2875);
DISPLAY 0.489362 (-3525 2875);
PAINT SKYBLUE (-3525 2875);
FORCEPROP 1 LAST VOLTAGE 16V
J 0
(-3525 2825);
DISPLAY 0.489362 (-3525 2825);
PAINT SKYBLUE (-3525 2825);
FORCEPROP 1 LAST TOLERANCE 20%
J 0
(-3525 2775);
DISPLAY 0.489362 (-3525 2775);
PAINT SKYBLUE (-3525 2775);
FORCEPROP 2 LAST CDS_LIB pure_quanta
J 0
(-3575 2825);
DISPLAY INVISIBLE (-3575 2825);
FORCEPROP 1 LAST PATH I55
J 0
(-3525 2975);
DISPLAY 0.978723 (-3525 2975);
PAINT WHITE (-3525 2975);
DISPLAY INVISIBLE (-3525 2975);
FORCEPROP 1 LAST PART_NUMBER CH6223MEA01
J 0
(-3525 2675);
DISPLAY 0.489362 (-3525 2675);
PAINT SKYBLUE (-3525 2675);
DISPLAY INVISIBLE (-3525 2675);
FORCEADD VCC_CORE..1
(-3575 3125);
FORCEPROP 3 LASTPIN (-3575 3075) SIG_NAME SW_P12V_AUX_PVDDCR_CPU0_P1_FLT\g
J 0
(-3565 3085);
DISPLAY 0.659574 (-3565 3085);
PAINT MONO (-3565 3085);
DISPLAY INVISIBLE (-3565 3085);
FORCEPROP 1 LAST HDL_POWER SW_P12V_AUX_PVDDCR_CPU0_P1_FLT
J 1
(-3575 3175);
DISPLAY 0.489362 (-3575 3175);
PAINT GREEN (-3575 3175);
FORCEPROP 2 LAST CDS_LIB pure_quanta_power
J 0
(-3575 3125);
DISPLAY INVISIBLE (-3575 3125);
FORCEPROP 1 LAST PATH I56
J 0
(-3525 3150);
DISPLAY 0.872340 (-3525 3150);
PAINT AQUA (-3525 3150);
DISPLAY INVISIBLE (-3525 3150);
FORCEADD OFFPAGE..3
(-1475 1700);
FORCEPROP 2 LAST $XR0 213 
J 0
(-1261 1700);
DISPLAY 0.638298 (-1261 1700);
PAINT MONO (-1261 1700);
FORCEPROP 2 LAST CDS_LIB standard
J 2
(-1475 1700);
DISPLAY INVISIBLE (-1475 1700);
FORCEPROP 1 LAST OFFPAGE TRUE
J 0
(-1150 1575);
DISPLAY 0.872340 (-1150 1575);
PAINT GREEN (-1150 1575);
DISPLAY INVISIBLE (-1150 1575);
FORCEPROP 1 LAST COMMENT_BODY TRUE
J 0
(-1525 1600);
DISPLAY 0.872340 (-1525 1600);
PAINT GREEN (-1525 1600);
DISPLAY INVISIBLE (-1525 1600);
FORCEPROP 2 LAST PATH I57
J 0
(-1250 1750);
DISPLAY 0.680851 (-1250 1750);
DISPLAY INVISIBLE (-1250 1750);
FORCEADD Q_CAP..1
(-1125 1775);
FORCEPROP 1 LAST LOCATION PC134_6
J 0
(-1075 1875);
DISPLAY 0.489362 (-1075 1875);
PAINT SKYBLUE (-1075 1875);
FORCEPROP 0 LAST $SEC 1
J 0
(-1075 1900);
DISPLAY 0.680851 (-1075 1900);
PAINT MONO (-1075 1900);
DISPLAY INVISIBLE (-1075 1900);
FORCEPROP 0 LAST CDS_SEC 1
J 0
(-1075 1900);
DISPLAY 1.021277 (-1075 1900);
DISPLAY INVISIBLE (-1075 1900);
FORCEPROP 1 LASTPIN (-1125 1875) $PN 1
J 0
(-1115 1855);
DISPLAY 0.489362 (-1115 1855);
PAINT MONO (-1115 1855);
FORCEPROP 1 LASTPIN (-1125 1675) $PN 2
J 0
(-1115 1655);
DISPLAY 0.489362 (-1115 1655);
PAINT MONO (-1115 1655);
FORCEPROP 1 LAST VOLTAGE 4V
J 0
(-1075 1775);
DISPLAY 0.489362 (-1075 1775);
PAINT SKYBLUE (-1075 1775);
FORCEPROP 1 LAST VALUE 22UF
J 0
(-1075 1825);
DISPLAY 0.489362 (-1075 1825);
PAINT SKYBLUE (-1075 1825);
FORCEPROP 1 LAST TOLERANCE 20%
J 0
(-1075 1725);
DISPLAY 0.489362 (-1075 1725);
PAINT SKYBLUE (-1075 1725);
FORCEPROP 1 LAST MATERIAL X6S
J 0
(-1075 1675);
DISPLAY 0.489362 (-1075 1675);
PAINT SKYBLUE (-1075 1675);
FORCEPROP 1 LAST PACK_TYPE C0805
J 0
(-1075 1575);
DISPLAY 0.489362 (-1075 1575);
PAINT SKYBLUE (-1075 1575);
FORCEPROP 2 LAST CDS_LIB pure_quanta
J 0
(-1125 1775);
DISPLAY INVISIBLE (-1125 1775);
FORCEPROP 1 LAST PATH I58
J 0
(-1075 1925);
DISPLAY 0.978723 (-1075 1925);
PAINT WHITE (-1075 1925);
DISPLAY INVISIBLE (-1075 1925);
FORCEPROP 1 LAST PART_NUMBER CH622KMEA03
J 0
(-1075 1625);
DISPLAY 0.489362 (-1075 1625);
PAINT SKYBLUE (-1075 1625);
DISPLAY INVISIBLE (-1075 1625);
FORCEADD UNIVERSAL_GND..1
(-700 1425);
FORCEPROP 3 LASTPIN (-700 1475) SIG_NAME GND\g
J 0
(-690 1485);
DISPLAY 0.659574 (-690 1485);
PAINT MONO (-690 1485);
DISPLAY INVISIBLE (-690 1485);
FORCEPROP 2 LAST CDS_LIB pure_quanta_power
J 0
(-700 1425);
DISPLAY INVISIBLE (-700 1425);
FORCEPROP 1 LAST HDL_POWER GND
J 1
(-675 1350);
DISPLAY 0.872340 (-675 1350);
PAINT GREEN (-675 1350);
DISPLAY INVISIBLE (-675 1350);
FORCEPROP 1 LAST PATH I59
J 0
(-625 1425);
DISPLAY 0.872340 (-625 1425);
PAINT AQUA (-625 1425);
DISPLAY INVISIBLE (-625 1425);
FORCEADD OFFPAGE..2
R 2
(-6775 1450);
FORCEPROP 2 LAST $XR3 210 
J 0
(-7270 1414);
DISPLAY 0.638298 (-7270 1414);
PAINT MONO (-7270 1414);
FORCEPROP 2 LAST $XR2 213 
J 0
(-7150 1414);
DISPLAY 0.638298 (-7150 1414);
PAINT MONO (-7150 1414);
FORCEPROP 2 LAST $XR1 212 
J 0
(-7030 1414);
DISPLAY 0.638298 (-7030 1414);
PAINT MONO (-7030 1414);
FORCEPROP 2 LAST $XR0 211 
J 0
(-7030 1450);
DISPLAY 0.638298 (-7030 1450);
PAINT MONO (-7030 1450);
FORCEPROP 2 LAST CDS_LIB standard
J 0
(-6775 1450);
DISPLAY INVISIBLE (-6775 1450);
FORCEPROP 1 LAST OFFPAGE TRUE
J 2
(-7100 1325);
DISPLAY 0.872340 (-7100 1325);
PAINT GREEN (-7100 1325);
DISPLAY INVISIBLE (-7100 1325);
FORCEPROP 1 LAST COMMENT_BODY TRUE
J 2
(-6730 1355);
DISPLAY 0.872340 (-6730 1355);
PAINT GREEN (-6730 1355);
DISPLAY INVISIBLE (-6730 1355);
FORCEPROP 2 LAST PATH I6
J 0
(-7050 1500);
DISPLAY 0.680851 (-7050 1500);
DISPLAY INVISIBLE (-7050 1500);
FORCEADD Q_CAP..1
(-700 1775);
FORCEPROP 1 LAST LOCATION PC135_6
J 0
(-650 1875);
DISPLAY 0.489362 (-650 1875);
PAINT SKYBLUE (-650 1875);
FORCEPROP 0 LAST $SEC 1
J 0
(-650 1900);
DISPLAY 0.680851 (-650 1900);
PAINT MONO (-650 1900);
DISPLAY INVISIBLE (-650 1900);
FORCEPROP 0 LAST CDS_SEC 1
J 0
(-650 1900);
DISPLAY 1.021277 (-650 1900);
DISPLAY INVISIBLE (-650 1900);
FORCEPROP 1 LASTPIN (-700 1875) $PN 1
J 0
(-690 1855);
DISPLAY 0.489362 (-690 1855);
PAINT MONO (-690 1855);
FORCEPROP 1 LASTPIN (-700 1675) $PN 2
J 0
(-690 1655);
DISPLAY 0.489362 (-690 1655);
PAINT MONO (-690 1655);
FORCEPROP 1 LAST VOLTAGE 4V
J 0
(-650 1775);
DISPLAY 0.489362 (-650 1775);
PAINT SKYBLUE (-650 1775);
FORCEPROP 1 LAST TOLERANCE 20%
J 0
(-650 1725);
DISPLAY 0.489362 (-650 1725);
PAINT SKYBLUE (-650 1725);
FORCEPROP 1 LAST MATERIAL X6S
J 0
(-650 1675);
DISPLAY 0.489362 (-650 1675);
PAINT SKYBLUE (-650 1675);
FORCEPROP 1 LAST PACK_TYPE C0805
J 0
(-650 1575);
DISPLAY 0.489362 (-650 1575);
PAINT SKYBLUE (-650 1575);
FORCEPROP 1 LAST VALUE 22UF
J 0
(-650 1825);
DISPLAY 0.489362 (-650 1825);
PAINT SKYBLUE (-650 1825);
FORCEPROP 2 LAST CDS_LIB pure_quanta
J 0
(-700 1775);
DISPLAY INVISIBLE (-700 1775);
FORCEPROP 1 LAST PATH I60
J 0
(-650 1925);
DISPLAY 0.978723 (-650 1925);
PAINT WHITE (-650 1925);
DISPLAY INVISIBLE (-650 1925);
FORCEPROP 1 LAST PART_NUMBER CH622KMEA03
J 0
(-650 1625);
DISPLAY 0.489362 (-650 1625);
PAINT SKYBLUE (-650 1625);
DISPLAY INVISIBLE (-650 1625);
FORCEADD VCC_CORE..1
(-700 2100);
FORCEPROP 3 LASTPIN (-700 2050) SIG_NAME PVDDCR_CPU0_P1\g
J 0
(-690 2060);
DISPLAY 0.659574 (-690 2060);
PAINT MONO (-690 2060);
DISPLAY INVISIBLE (-690 2060);
FORCEPROP 1 LAST HDL_POWER PVDDCR_CPU0_P1
J 1
(-700 2150);
DISPLAY 0.489362 (-700 2150);
PAINT GREEN (-700 2150);
FORCEPROP 2 LAST CDS_LIB pure_quanta_power
J 0
(-700 2100);
DISPLAY INVISIBLE (-700 2100);
FORCEPROP 1 LAST PATH I61
J 0
(-650 2125);
DISPLAY 0.872340 (-650 2125);
PAINT AQUA (-650 2125);
DISPLAY INVISIBLE (-650 2125);
FORCEADD OFFPAGE..3
R 2
(-3375 4600);
FORCEPROP 2 LAST $XR0 213 
J 0
(-3655 4600);
DISPLAY 0.638298 (-3655 4600);
PAINT MONO (-3655 4600);
FORCEPROP 2 LAST CDS_LIB standard
J 2
(-3375 4600);
DISPLAY INVISIBLE (-3375 4600);
FORCEPROP 1 LAST OFFPAGE TRUE
J 2
(-3700 4475);
DISPLAY 0.872340 (-3700 4475);
PAINT GREEN (-3700 4475);
DISPLAY INVISIBLE (-3700 4475);
FORCEPROP 1 LAST COMMENT_BODY TRUE
J 2
(-3325 4500);
DISPLAY 0.872340 (-3325 4500);
PAINT GREEN (-3325 4500);
DISPLAY INVISIBLE (-3325 4500);
FORCEPROP 2 LAST PATH I62
J 0
(-3675 4650);
DISPLAY 0.680851 (-3675 4650);
DISPLAY INVISIBLE (-3675 4650);
FORCEADD Q_CAP..1
(-3325 5075);
FORCEPROP 1 LAST LOCATION PC314
J 0
(-3275 5200);
DISPLAY 0.489362 (-3275 5200);
PAINT SKYBLUE (-3275 5200);
FORCEPROP 0 LAST $SEC 1
J 0
(-3275 5225);
DISPLAY 0.680851 (-3275 5225);
PAINT MONO (-3275 5225);
DISPLAY INVISIBLE (-3275 5225);
FORCEPROP 0 LAST CDS_SEC 1
J 0
(-3275 5225);
DISPLAY 1.021277 (-3275 5225);
DISPLAY INVISIBLE (-3275 5225);
FORCEPROP 1 LASTPIN (-3325 5175) $PN 1
J 0
(-3315 5155);
DISPLAY 0.489362 (-3315 5155);
PAINT MONO (-3315 5155);
FORCEPROP 1 LASTPIN (-3325 4975) $PN 2
J 0
(-3315 4955);
DISPLAY 0.489362 (-3315 4955);
PAINT MONO (-3315 4955);
FORCEPROP 1 LAST PACK_TYPE 0402
J 0
(-3275 4900);
DISPLAY 0.489362 (-3275 4900);
PAINT SKYBLUE (-3275 4900);
FORCEPROP 1 LAST VALUE 0.22UF
J 0
(-3275 5150);
DISPLAY 0.489362 (-3275 5150);
PAINT SKYBLUE (-3275 5150);
FORCEPROP 1 LAST VOLTAGE 16V
J 0
(-3275 5100);
DISPLAY 0.489362 (-3275 5100);
PAINT SKYBLUE (-3275 5100);
FORCEPROP 1 LAST TOLERANCE 10%
J 0
(-3275 5050);
DISPLAY 0.489362 (-3275 5050);
PAINT SKYBLUE (-3275 5050);
FORCEPROP 1 LAST MATERIAL X7R
J 0
(-3275 5000);
DISPLAY 0.489362 (-3275 5000);
PAINT SKYBLUE (-3275 5000);
FORCEPROP 2 LAST CDS_LIB pure_quanta
J 0
(-3325 5075);
DISPLAY INVISIBLE (-3325 5075);
FORCEPROP 1 LAST PATH I63
J 0
(-3275 5225);
DISPLAY 0.978723 (-3275 5225);
PAINT WHITE (-3275 5225);
DISPLAY INVISIBLE (-3275 5225);
FORCEPROP 1 LAST PART_NUMBER CH4223K1B00
J 0
(-3275 4950);
DISPLAY 0.489362 (-3275 4950);
PAINT SKYBLUE (-3275 4950);
DISPLAY INVISIBLE (-3275 4950);
FORCEADD Q_INDUCTOR4P_14..1
(-2475 4725);
FORCEPROP 1 LAST LOCATION PL33
J 0
(-2700 4980);
DISPLAY 0.489362 (-2700 4980);
PAINT SKYBLUE (-2700 4980);
FORCEPROP 0 LAST $SEC 1
J 0
(-2700 5125);
DISPLAY 0.680851 (-2700 5125);
PAINT MONO (-2700 5125);
DISPLAY INVISIBLE (-2700 5125);
FORCEPROP 0 LAST CDS_SEC 1
J 0
(-2700 5125);
DISPLAY 1.021277 (-2700 5125);
DISPLAY INVISIBLE (-2700 5125);
FORCEPROP 0 LASTPIN (-2875 4850) $PN 1
J 2
(-2885 4860);
DISPLAY 0.489362 (-2885 4860);
PAINT MONO (-2885 4860);
FORCEPROP 0 LASTPIN (-2875 4600) $PN 2
J 2
(-2885 4610);
DISPLAY 0.489362 (-2885 4610);
PAINT MONO (-2885 4610);
FORCEPROP 0 LASTPIN (-2075 4600) $PN 3
J 0
(-2065 4610);
DISPLAY 0.489362 (-2065 4610);
PAINT MONO (-2065 4610);
FORCEPROP 0 LASTPIN (-2075 4850) $PN 4
J 0
(-2065 4860);
DISPLAY 0.489362 (-2065 4860);
PAINT MONO (-2065 4860);
FORCEPROP 2 LAST PART_TYPE SMLF
J 0
(-2700 5075);
DISPLAY 1.021277 (-2700 5075);
FORCEPROP 2 LAST VALUE 150NH
J 0
(-2700 5025);
DISPLAY 0.489362 (-2700 5025);
PAINT SKYBLUE (-2700 5025);
FORCEPROP 1 LAST MATERIAL IND
J 0
(-2700 4935);
DISPLAY 0.489362 (-2700 4935);
PAINT SKYBLUE (-2700 4935);
FORCEPROP 2 LAST CDS_LIB pure_quanta
J 0
(-2475 4725);
DISPLAY INVISIBLE (-2475 4725);
FORCEPROP 1 LAST NEEDS_NO_SIZE TRUE
J 0
(-2475 4725);
DISPLAY 0.468085 (-2475 4725);
PAINT GREEN (-2475 4725);
DISPLAY INVISIBLE (-2475 4725);
FORCEPROP 1 LAST PATH I64
J 0
(-2275 4880);
DISPLAY 0.723404 (-2275 4880);
PAINT GREEN (-2275 4880);
DISPLAY INVISIBLE (-2275 4880);
FORCEPROP 1 LAST PART_NUMBER CV+15^0TZ04
J 0
(-2700 4885);
DISPLAY 0.489362 (-2700 4885);
PAINT SKYBLUE (-2700 4885);
DISPLAY INVISIBLE (-2700 4885);
FORCEADD UNIVERSAL_GND..1
(-3625 5375);
FORCEPROP 3 LASTPIN (-3625 5425) SIG_NAME GND\g
J 0
(-3615 5435);
DISPLAY 0.659574 (-3615 5435);
PAINT MONO (-3615 5435);
DISPLAY INVISIBLE (-3615 5435);
FORCEPROP 2 LAST CDS_LIB pure_quanta_power
J 0
(-3625 5375);
DISPLAY INVISIBLE (-3625 5375);
FORCEPROP 1 LAST HDL_POWER GND
J 1
(-3600 5300);
DISPLAY 0.872340 (-3600 5300);
PAINT GREEN (-3600 5300);
DISPLAY INVISIBLE (-3600 5300);
FORCEPROP 1 LAST PATH I65
J 0
(-3550 5375);
DISPLAY 0.872340 (-3550 5375);
PAINT AQUA (-3550 5375);
DISPLAY INVISIBLE (-3550 5375);
FORCEADD Q_CAP..1
(-3625 5725);
FORCEPROP 1 LAST LOCATION PC313_5
J 0
(-3575 5825);
DISPLAY 0.489362 (-3575 5825);
PAINT SKYBLUE (-3575 5825);
FORCEPROP 0 LAST $SEC 1
J 0
(-3575 5850);
DISPLAY 0.680851 (-3575 5850);
PAINT MONO (-3575 5850);
DISPLAY INVISIBLE (-3575 5850);
FORCEPROP 0 LAST CDS_SEC 1
J 0
(-3575 5850);
DISPLAY 1.021277 (-3575 5850);
DISPLAY INVISIBLE (-3575 5850);
FORCEPROP 1 LASTPIN (-3625 5825) $PN 1
J 0
(-3615 5805);
DISPLAY 0.489362 (-3615 5805);
PAINT MONO (-3615 5805);
FORCEPROP 1 LASTPIN (-3625 5625) $PN 2
J 0
(-3615 5605);
DISPLAY 0.489362 (-3615 5605);
PAINT MONO (-3615 5605);
FORCEPROP 1 LAST PACK_TYPE C0805
J 0
(-3575 5525);
DISPLAY 0.489362 (-3575 5525);
PAINT SKYBLUE (-3575 5525);
FORCEPROP 1 LAST VALUE 22UF
J 0
(-3575 5775);
DISPLAY 0.489362 (-3575 5775);
PAINT SKYBLUE (-3575 5775);
FORCEPROP 1 LAST VOLTAGE 16V
J 0
(-3575 5725);
DISPLAY 0.489362 (-3575 5725);
PAINT SKYBLUE (-3575 5725);
FORCEPROP 1 LAST TOLERANCE 20%
J 0
(-3575 5675);
DISPLAY 0.489362 (-3575 5675);
PAINT SKYBLUE (-3575 5675);
FORCEPROP 1 LAST MATERIAL X6S
J 0
(-3575 5625);
DISPLAY 0.489362 (-3575 5625);
PAINT SKYBLUE (-3575 5625);
FORCEPROP 2 LAST CDS_LIB pure_quanta
J 0
(-3625 5725);
DISPLAY INVISIBLE (-3625 5725);
FORCEPROP 1 LAST PATH I66
J 0
(-3575 5875);
DISPLAY 0.978723 (-3575 5875);
PAINT WHITE (-3575 5875);
DISPLAY INVISIBLE (-3575 5875);
FORCEPROP 1 LAST PART_NUMBER CH6223MEA01
J 0
(-3575 5575);
DISPLAY 0.489362 (-3575 5575);
PAINT SKYBLUE (-3575 5575);
DISPLAY INVISIBLE (-3575 5575);
FORCEADD VCC_CORE..1
(-3625 6025);
FORCEPROP 3 LASTPIN (-3625 5975) SIG_NAME SW_P12V_AUX_PVDDCR_CPU0_P1_FLT\g
J 0
(-3615 5985);
DISPLAY 0.659574 (-3615 5985);
PAINT MONO (-3615 5985);
DISPLAY INVISIBLE (-3615 5985);
FORCEPROP 1 LAST HDL_POWER SW_P12V_AUX_PVDDCR_CPU0_P1_FLT
J 1
(-3625 6075);
DISPLAY 0.489362 (-3625 6075);
PAINT GREEN (-3625 6075);
FORCEPROP 2 LAST CDS_LIB pure_quanta_power
J 0
(-3625 6025);
DISPLAY INVISIBLE (-3625 6025);
FORCEPROP 1 LAST PATH I67
J 0
(-3575 6050);
DISPLAY 0.872340 (-3575 6050);
PAINT AQUA (-3575 6050);
DISPLAY INVISIBLE (-3575 6050);
FORCEADD OFFPAGE..3
(-1525 4600);
FORCEPROP 2 LAST $XR0 211 
J 0
(-1311 4600);
DISPLAY 0.638298 (-1311 4600);
PAINT MONO (-1311 4600);
FORCEPROP 2 LAST CDS_LIB standard
J 2
(-1525 4600);
DISPLAY INVISIBLE (-1525 4600);
FORCEPROP 1 LAST OFFPAGE TRUE
J 0
(-1200 4475);
DISPLAY 0.872340 (-1200 4475);
PAINT GREEN (-1200 4475);
DISPLAY INVISIBLE (-1200 4475);
FORCEPROP 1 LAST COMMENT_BODY TRUE
J 0
(-1575 4500);
DISPLAY 0.872340 (-1575 4500);
PAINT GREEN (-1575 4500);
DISPLAY INVISIBLE (-1575 4500);
FORCEPROP 2 LAST PATH I68
J 0
(-1300 4650);
DISPLAY 0.680851 (-1300 4650);
DISPLAY INVISIBLE (-1300 4650);
FORCEADD Q_CAP..1
(-1175 4675);
FORCEPROP 1 LAST LOCATION PC315_5
J 0
(-1125 4775);
DISPLAY 0.489362 (-1125 4775);
PAINT SKYBLUE (-1125 4775);
FORCEPROP 0 LAST $SEC 1
J 0
(-1125 4800);
DISPLAY 0.680851 (-1125 4800);
PAINT MONO (-1125 4800);
DISPLAY INVISIBLE (-1125 4800);
FORCEPROP 0 LAST CDS_SEC 1
J 0
(-1125 4800);
DISPLAY 1.021277 (-1125 4800);
DISPLAY INVISIBLE (-1125 4800);
FORCEPROP 1 LASTPIN (-1175 4775) $PN 1
J 0
(-1165 4755);
DISPLAY 0.489362 (-1165 4755);
PAINT MONO (-1165 4755);
FORCEPROP 1 LASTPIN (-1175 4575) $PN 2
J 0
(-1165 4555);
DISPLAY 0.489362 (-1165 4555);
PAINT MONO (-1165 4555);
FORCEPROP 1 LAST VOLTAGE 4V
J 0
(-1125 4675);
DISPLAY 0.489362 (-1125 4675);
PAINT SKYBLUE (-1125 4675);
FORCEPROP 1 LAST VALUE 22UF
J 0
(-1125 4725);
DISPLAY 0.489362 (-1125 4725);
PAINT SKYBLUE (-1125 4725);
FORCEPROP 1 LAST TOLERANCE 20%
J 0
(-1125 4625);
DISPLAY 0.489362 (-1125 4625);
PAINT SKYBLUE (-1125 4625);
FORCEPROP 1 LAST MATERIAL X6S
J 0
(-1125 4575);
DISPLAY 0.489362 (-1125 4575);
PAINT SKYBLUE (-1125 4575);
FORCEPROP 1 LAST PACK_TYPE C0805
J 0
(-1125 4475);
DISPLAY 0.489362 (-1125 4475);
PAINT SKYBLUE (-1125 4475);
FORCEPROP 2 LAST CDS_LIB pure_quanta
J 0
(-1175 4675);
DISPLAY INVISIBLE (-1175 4675);
FORCEPROP 1 LAST PATH I69
J 0
(-1125 4825);
DISPLAY 0.978723 (-1125 4825);
PAINT WHITE (-1125 4825);
DISPLAY INVISIBLE (-1125 4825);
FORCEPROP 1 LAST PART_NUMBER CH622KMEA03
J 0
(-1125 4525);
DISPLAY 0.489362 (-1125 4525);
PAINT SKYBLUE (-1125 4525);
DISPLAY INVISIBLE (-1125 4525);
FORCEADD OFFPAGE..1
(-6750 1350);
FORCEPROP 2 LAST $XR0 210 
J 0
(-7002 1350);
DISPLAY 0.638298 (-7002 1350);
PAINT MONO (-7002 1350);
FORCEPROP 2 LAST CDS_LIB standard
J 2
(-6750 1350);
DISPLAY INVISIBLE (-6750 1350);
FORCEPROP 1 LAST OFFPAGE TRUE
J 0
(-6425 1225);
DISPLAY 0.872340 (-6425 1225);
PAINT GREEN (-6425 1225);
DISPLAY INVISIBLE (-6425 1225);
FORCEPROP 1 LAST COMMENT_BODY TRUE
J 0
(-6625 1250);
DISPLAY 0.872340 (-6625 1250);
PAINT GREEN (-6625 1250);
DISPLAY INVISIBLE (-6625 1250);
FORCEPROP 2 LAST PATH I7
J 0
(-7025 1400);
DISPLAY 0.680851 (-7025 1400);
DISPLAY INVISIBLE (-7025 1400);
FORCEADD UNIVERSAL_GND..1
(-750 4325);
FORCEPROP 3 LASTPIN (-750 4375) SIG_NAME GND\g
J 0
(-740 4385);
DISPLAY 0.659574 (-740 4385);
PAINT MONO (-740 4385);
DISPLAY INVISIBLE (-740 4385);
FORCEPROP 2 LAST CDS_LIB pure_quanta_power
J 0
(-750 4325);
DISPLAY INVISIBLE (-750 4325);
FORCEPROP 1 LAST HDL_POWER GND
J 1
(-725 4250);
DISPLAY 0.872340 (-725 4250);
PAINT GREEN (-725 4250);
DISPLAY INVISIBLE (-725 4250);
FORCEPROP 1 LAST PATH I70
J 0
(-675 4325);
DISPLAY 0.872340 (-675 4325);
PAINT AQUA (-675 4325);
DISPLAY INVISIBLE (-675 4325);
FORCEADD Q_CAP..1
(-750 4675);
FORCEPROP 1 LAST LOCATION PC316_5
J 0
(-700 4775);
DISPLAY 0.489362 (-700 4775);
PAINT SKYBLUE (-700 4775);
FORCEPROP 0 LAST $SEC 1
J 0
(-700 4800);
DISPLAY 0.680851 (-700 4800);
PAINT MONO (-700 4800);
DISPLAY INVISIBLE (-700 4800);
FORCEPROP 0 LAST CDS_SEC 1
J 0
(-700 4800);
DISPLAY 1.021277 (-700 4800);
DISPLAY INVISIBLE (-700 4800);
FORCEPROP 1 LASTPIN (-750 4775) $PN 1
J 0
(-740 4755);
DISPLAY 0.489362 (-740 4755);
PAINT MONO (-740 4755);
FORCEPROP 1 LASTPIN (-750 4575) $PN 2
J 0
(-740 4555);
DISPLAY 0.489362 (-740 4555);
PAINT MONO (-740 4555);
FORCEPROP 1 LAST VOLTAGE 4V
J 0
(-700 4675);
DISPLAY 0.489362 (-700 4675);
PAINT SKYBLUE (-700 4675);
FORCEPROP 1 LAST VALUE 22UF
J 0
(-700 4725);
DISPLAY 0.489362 (-700 4725);
PAINT SKYBLUE (-700 4725);
FORCEPROP 1 LAST TOLERANCE 20%
J 0
(-700 4625);
DISPLAY 0.489362 (-700 4625);
PAINT SKYBLUE (-700 4625);
FORCEPROP 1 LAST MATERIAL X6S
J 0
(-700 4575);
DISPLAY 0.489362 (-700 4575);
PAINT SKYBLUE (-700 4575);
FORCEPROP 1 LAST PACK_TYPE C0805
J 0
(-700 4475);
DISPLAY 0.489362 (-700 4475);
PAINT SKYBLUE (-700 4475);
FORCEPROP 2 LAST CDS_LIB pure_quanta
J 0
(-750 4675);
DISPLAY INVISIBLE (-750 4675);
FORCEPROP 1 LAST PATH I71
J 0
(-700 4825);
DISPLAY 0.978723 (-700 4825);
PAINT WHITE (-700 4825);
DISPLAY INVISIBLE (-700 4825);
FORCEPROP 1 LAST PART_NUMBER CH622KMEA03
J 0
(-700 4525);
DISPLAY 0.489362 (-700 4525);
PAINT SKYBLUE (-700 4525);
DISPLAY INVISIBLE (-700 4525);
FORCEADD VCC_CORE..1
(-750 5000);
FORCEPROP 3 LASTPIN (-750 4950) SIG_NAME PVDDCR_CPU0_P1\g
J 0
(-740 4960);
DISPLAY 0.659574 (-740 4960);
PAINT MONO (-740 4960);
DISPLAY INVISIBLE (-740 4960);
FORCEPROP 1 LAST HDL_POWER PVDDCR_CPU0_P1
J 1
(-750 5050);
DISPLAY 0.489362 (-750 5050);
PAINT GREEN (-750 5050);
FORCEPROP 2 LAST CDS_LIB pure_quanta_power
J 0
(-750 5000);
DISPLAY INVISIBLE (-750 5000);
FORCEPROP 1 LAST PATH I72
J 0
(-700 5025);
DISPLAY 0.872340 (-700 5025);
PAINT AQUA (-700 5025);
DISPLAY INVISIBLE (-700 5025);
FORCEADD ISL99390FRZTR5935..1
(-5650 1950);
FORCEPROP 1 LAST LOCATION PU24
J 0
(-5950 2825);
DISPLAY 0.489362 (-5950 2825);
PAINT SKYBLUE (-5950 2825);
FORCEPROP 0 LAST $SEC 1
J 0
(-5950 2975);
DISPLAY 0.680851 (-5950 2975);
PAINT MONO (-5950 2975);
DISPLAY INVISIBLE (-5950 2975);
FORCEPROP 2 LAST CDS_SEC 1
J 0
(-5950 2975);
DISPLAY 1.021277 (-5950 2975);
DISPLAY INVISIBLE (-5950 2975);
FORCEPROP 0 LASTPIN (-5250 1500) $PN 2
J 0
(-5240 1510);
DISPLAY 0.489362 (-5240 1510);
PAINT MONO (-5240 1510);
FORCEPROP 0 LASTPIN (-5250 2300) $PN 33
J 0
(-5240 2310);
DISPLAY 0.489362 (-5240 2310);
PAINT MONO (-5240 2310);
FORCEPROP 0 LASTPIN (-6100 1700) $PN 31
J 2
(-6110 1710);
DISPLAY 0.489362 (-6110 1710);
PAINT MONO (-6110 1710);
FORCEPROP 0 LASTPIN (-6100 2100) $PN 35
J 2
(-6110 2110);
DISPLAY 0.489362 (-6110 2110);
PAINT MONO (-6110 2110);
FORCEPROP 0 LASTPIN (-5250 1650) $PN 6
J 0
(-5240 1660);
DISPLAY 0.489362 (-5240 1660);
PAINT MONO (-5240 1660);
FORCEPROP 0 LASTPIN (-5250 1600) $PN 41
J 0
(-5240 1610);
DISPLAY 0.489362 (-5240 1610);
PAINT MONO (-5240 1610);
FORCEPROP 0 LASTPIN (-6100 1950) $PN 38
J 2
(-6110 1960);
DISPLAY 0.489362 (-6110 1960);
PAINT MONO (-6110 1960);
FORCEPROP 0 LASTPIN (-6100 1650) $PN 37
J 2
(-6110 1660);
DISPLAY 0.489362 (-6110 1660);
PAINT MONO (-6110 1660);
FORCEPROP 0 LASTPIN (-5250 1450) $PN 5
J 0
(-5240 1460);
DISPLAY 0.489362 (-5240 1460);
PAINT MONO (-5240 1460);
FORCEPROP 0 LASTPIN (-5250 1400) $PN 7_9-20_24
J 0
(-5240 1410);
DISPLAY 0.489362 (-5240 1410);
PAINT MONO (-5240 1410);
FORCEPROP 0 LASTPIN (-5250 1350) $PN 40
J 0
(-5240 1360);
DISPLAY 0.489362 (-5240 1360);
PAINT MONO (-5240 1360);
FORCEPROP 0 LASTPIN (-5250 2050) $PN 32
J 0
(-5240 2060);
DISPLAY 0.489362 (-5240 2060);
PAINT MONO (-5240 2060);
FORCEPROP 0 LASTPIN (-6100 2600) $PN 4
J 2
(-6110 2610);
DISPLAY 0.489362 (-6110 2610);
PAINT MONO (-6110 2610);
FORCEPROP 0 LASTPIN (-6100 1350) $PN 34
J 2
(-6110 1360);
DISPLAY 0.489362 (-6110 1360);
PAINT MONO (-6110 1360);
FORCEPROP 0 LASTPIN (-6100 1850) $PN 39
J 2
(-6110 1860);
DISPLAY 0.489362 (-6110 1860);
PAINT MONO (-6110 1860);
FORCEPROP 0 LASTPIN (-5250 1950) $PN 10_19
J 0
(-5240 1960);
DISPLAY 0.489362 (-5240 1960);
PAINT MONO (-5240 1960);
FORCEPROP 0 LASTPIN (-6100 1450) $PN 36
J 2
(-6110 1460);
DISPLAY 0.489362 (-6110 1460);
PAINT MONO (-6110 1460);
FORCEPROP 0 LASTPIN (-6100 2300) $PN 3
J 2
(-6110 2310);
DISPLAY 0.489362 (-6110 2310);
PAINT MONO (-6110 2310);
FORCEPROP 0 LASTPIN (-5250 2600) $PN 25_29
J 0
(-5240 2610);
DISPLAY 0.489362 (-5240 2610);
PAINT MONO (-5240 2610);
FORCEPROP 0 LASTPIN (-5250 2550) $PN 30
J 0
(-5240 2560);
DISPLAY 0.489362 (-5240 2560);
PAINT MONO (-5240 2560);
FORCEPROP 0 LASTPIN (-5250 1700) $PN 1
J 0
(-5240 1710);
DISPLAY 0.489362 (-5240 1710);
PAINT MONO (-5240 1710);
FORCEPROP 2 LAST PART_TYPE SMLF
J 0
(-5950 2925);
DISPLAY 1.021277 (-5950 2925);
FORCEPROP 1 LAST MATERIAL IC
J 0
(-5950 2675);
DISPLAY 0.489362 (-5950 2675);
PAINT SKYBLUE (-5950 2675);
FORCEPROP 2 LAST VALUE ISL99390FRZ-TR5935
J 0
(-5950 2875);
DISPLAY 0.489362 (-5950 2875);
PAINT SKYBLUE (-5950 2875);
FORCEPROP 2 LAST CDS_LIB pure_quanta
J 0
(-5650 1950);
DISPLAY INVISIBLE (-5650 1950);
FORCEPROP 1 LAST NEEDS_NO_SIZE TRUE
J 0
(-5650 1950);
DISPLAY 0.723404 (-5650 1950);
PAINT GREEN (-5650 1950);
DISPLAY INVISIBLE (-5650 1950);
FORCEPROP 1 LAST CDS_LMAN_SYM_OUTLINE -300,700,250,-650
J 0
(-5650 1950);
DISPLAY 0.468085 (-5650 1950);
PAINT GREEN (-5650 1950);
DISPLAY INVISIBLE (-5650 1950);
FORCEPROP 1 LAST PATH I73
J 0
(-5650 1950);
DISPLAY 0.723404 (-5650 1950);
PAINT GREEN (-5650 1950);
DISPLAY INVISIBLE (-5650 1950);
FORCEPROP 1 LAST PART_NUMBER AL099390004
J 0
(-5950 2750);
DISPLAY 0.489362 (-5950 2750);
PAINT SKYBLUE (-5950 2750);
DISPLAY INVISIBLE (-5950 2750);
FORCEADD Q_RES..1
(-6825 1650);
FORCEPROP 1 LAST LOCATION PR423
J 0
(-6850 1700);
DISPLAY 0.489362 (-6850 1700);
PAINT SKYBLUE (-6850 1700);
FORCEPROP 0 LAST $SEC 1
J 0
(-6825 1725);
DISPLAY 0.680851 (-6825 1725);
PAINT MONO (-6825 1725);
DISPLAY INVISIBLE (-6825 1725);
FORCEPROP 0 LAST CDS_SEC 1
J 0
(-6825 1725);
DISPLAY 1.021277 (-6825 1725);
DISPLAY INVISIBLE (-6825 1725);
FORCEPROP 1 LASTPIN (-6925 1650) $PN 1
J 0
(-6913 1662);
DISPLAY 0.489362 (-6913 1662);
PAINT MONO (-6913 1662);
FORCEPROP 1 LASTPIN (-6725 1650) $PN 2
J 0
(-6763 1662);
DISPLAY 0.489362 (-6763 1662);
PAINT MONO (-6763 1662);
FORCEPROP 1 LAST WATTAGE 1/16W
J 0
(-6725 1550);
DISPLAY 0.489362 (-6725 1550);
PAINT SKYBLUE (-6725 1550);
FORCEPROP 1 LAST MATERIAL EMPTY
J 0
(-7125 1550);
DISPLAY 0.489362 (-7125 1550);
PAINT RED (-7125 1550);
FORCEPROP 1 LAST TOLERANCE 1%
J 0
(-6700 1675);
DISPLAY 0.489362 (-6700 1675);
PAINT SKYBLUE (-6700 1675);
FORCEPROP 1 LAST VALUE 8.87K
J 2
(-6950 1675);
DISPLAY 0.489362 (-6950 1675);
PAINT SKYBLUE (-6950 1675);
FORCEPROP 1 LAST PACK_TYPE 0402LF
J 0
(-6725 1600);
DISPLAY 0.489362 (-6725 1600);
PAINT SKYBLUE (-6725 1600);
FORCEPROP 2 LAST CDS_LIB pure_quanta
J 0
(-6825 1650);
DISPLAY INVISIBLE (-6825 1650);
FORCEPROP 1 LAST PATH I8
J 0
(-6875 1800);
DISPLAY 0.978723 (-6875 1800);
PAINT WHITE (-6875 1800);
DISPLAY INVISIBLE (-6875 1800);
FORCEPROP 1 LAST PART_NUMBER CS28872FB01
J 0
(-7125 1600);
DISPLAY 0.489362 (-7125 1600);
PAINT SKYBLUE (-7125 1600);
DISPLAY INVISIBLE (-7125 1600);
FORCEADD UNIVERSAL_GND..1
(-7150 2100);
FORCEPROP 3 LASTPIN (-7150 2150) SIG_NAME GND\g
J 0
(-7140 2160);
DISPLAY 0.659574 (-7140 2160);
PAINT MONO (-7140 2160);
DISPLAY INVISIBLE (-7140 2160);
FORCEPROP 2 LAST CDS_LIB pure_quanta_power
J 0
(-7150 2100);
DISPLAY INVISIBLE (-7150 2100);
FORCEPROP 1 LAST HDL_POWER GND
J 1
(-7125 2025);
DISPLAY 0.872340 (-7125 2025);
PAINT GREEN (-7125 2025);
DISPLAY INVISIBLE (-7125 2025);
FORCEPROP 1 LAST PATH I9
J 0
(-7075 2100);
DISPLAY 0.872340 (-7075 2100);
PAINT AQUA (-7075 2100);
DISPLAY INVISIBLE (-7075 2100);
FORCEADD QUANTA_TITLE_BLOCK_C..1
(0 0);
FORCEPROP 0 LAST CDS_CON_LAST_MODIFIED Thu Sep 14 16:12:41 2023
J 0
(-1885 15);
DISPLAY INVISIBLE (-1885 15);
FORCEPROP 1 LAST CUSTOM_TXT_CDS <CON_LAST_MODIFIED>
J 0
(-1885 15);
DISPLAY 0.978723 (-1885 15);
FORCEPROP 2 LAST CUSTOM_TXT_CDS <XR_PAGE_TITLE>
J 0
(-7890 5250);
DISPLAY 0.638298 (-7890 5250);
PAINT PINK (-7890 5250);
DISPLAY INVISIBLE (-7890 5250);
FORCEPROP 1 LAST CUSTOM_TXT_CDS <NAME_2>
J 0
(-3175 50);
FORCEPROP 1 LAST CUSTOM_TXT_CDS <NAME_1>
J 0
(-3175 175);
FORCEPROP 1 LAST CUSTOM_TXT_CDS <Q_NUMBER>
J 0
(-1403 103);
DISPLAY 1.212766 (-1403 103);
FORCEPROP 1 LAST CUSTOM_TXT_CDS <Q_PROJ>
J 0
(-2382 102);
DISPLAY 1.212766 (-2382 102);
FORCEPROP 1 LAST CUSTOM_TXT_CDS <Q_REV>
J 0
(-184 103);
DISPLAY 1.212766 (-184 103);
FORCEPROP 1 LAST CUSTOM_TXT_CDS <CON_PAGE_NUM> OF <CON_TOTAL_PAGES>
J 0
(-446 18);
DISPLAY 0.978723 (-446 18);
FORCEPROP 1 LAST Q_TITLE PVDDCR_CPU0_P1 VR PHASE 5&6
J 0
(-9325 50);
DISPLAY 2.446809 (-9325 50);
PAINT GREEN (-9325 50);
FORCEPROP 2 LAST PAGE_BORDER TRUE
J 0
(-7890 5250);
DISPLAY 0.638298 (-7890 5250);
PAINT PINK (-7890 5250);
DISPLAY INVISIBLE (-7890 5250);
FORCEPROP 2 LAST CDS_LIB pure_quanta
J 0
(0 0);
DISPLAY INVISIBLE (0 0);
FORCEPROP 1 LAST CDS_LMAN_SYM_OUTLINE -9475,6775,100,-125
J 0
(0 0);
DISPLAY 0.468085 (0 0);
PAINT GREEN (0 0);
DISPLAY INVISIBLE (0 0);
FORCEPROP 2 LAST CDS_XR_PAGE_TITLE CR-213 : @T6G_MB_LIB.T6G(SCH_1):PAGE213
J 0
(-7890 5250);
DISPLAY 0.638298 (-7890 5250);
PAINT PINK (-7890 5250);
DISPLAY INVISIBLE (-7890 5250);
FORCEPROP 1 LAST Q_DEPT BU9
J 1
(-3763 49);
DISPLAY 1.957447 (-3763 49);
PAINT GREEN (-3763 49);
DISPLAY INVISIBLE (-3763 49);
FORCEPROP 1 LAST COMMENT_BODY TRUE
J 0
(12 -13);
DISPLAY 0.978723 (12 -13);
PAINT GREEN (12 -13);
DISPLAY INVISIBLE (12 -13);
FORCEADD DNS..1
(-4300 4650);
PAINT RED (-4300 4650);
FORCEPROP 2 LAST CDS_LIB mstr_misc
J 0
(-4300 4650);
DISPLAY INVISIBLE (-4300 4650);
FORCEPROP 1 LAST COMMENT_BODY TRUE
R 1
J 0
(-4225 4425);
DISPLAY 0.872340 (-4225 4425);
PAINT GREEN (-4225 4425);
DISPLAY INVISIBLE (-4225 4425);
FORCEADD DNS..1
(-6875 4525);
PAINT RED (-6875 4525);
FORCEPROP 2 LAST CDS_LIB mstr_misc
J 0
(-6875 4525);
DISPLAY INVISIBLE (-6875 4525);
FORCEPROP 1 LAST COMMENT_BODY TRUE
R 1
J 0
(-6800 4300);
DISPLAY 0.872340 (-6800 4300);
PAINT GREEN (-6800 4300);
DISPLAY INVISIBLE (-6800 4300);
FORCEADD DNS..1
(-4300 4125);
PAINT RED (-4300 4125);
FORCEPROP 2 LAST CDS_LIB mstr_misc
J 0
(-4300 4125);
DISPLAY INVISIBLE (-4300 4125);
FORCEPROP 1 LAST COMMENT_BODY TRUE
R 1
J 0
(-4225 3900);
DISPLAY 0.872340 (-4225 3900);
PAINT GREEN (-4225 3900);
DISPLAY INVISIBLE (-4225 3900);
FORCEADD DNS..1
(-4250 1750);
PAINT RED (-4250 1750);
FORCEPROP 2 LAST CDS_LIB mstr_misc
J 0
(-4250 1750);
DISPLAY INVISIBLE (-4250 1750);
FORCEPROP 1 LAST COMMENT_BODY TRUE
R 1
J 0
(-4175 1525);
DISPLAY 0.872340 (-4175 1525);
PAINT GREEN (-4175 1525);
DISPLAY INVISIBLE (-4175 1525);
FORCEADD DNS..1
(-4250 1250);
PAINT RED (-4250 1250);
FORCEPROP 2 LAST CDS_LIB mstr_misc
J 0
(-4250 1250);
DISPLAY INVISIBLE (-4250 1250);
FORCEPROP 1 LAST COMMENT_BODY TRUE
R 1
J 0
(-4175 1025);
DISPLAY 0.872340 (-4175 1025);
PAINT GREEN (-4175 1025);
DISPLAY INVISIBLE (-4175 1025);
FORCEADD DNS..1
(-6825 1625);
PAINT RED (-6825 1625);
FORCEPROP 2 LAST CDS_LIB mstr_misc
J 0
(-6825 1625);
DISPLAY INVISIBLE (-6825 1625);
FORCEPROP 1 LAST COMMENT_BODY TRUE
R 1
J 0
(-6750 1400);
DISPLAY 0.872340 (-6750 1400);
PAINT GREEN (-6750 1400);
DISPLAY INVISIBLE (-6750 1400);
WIRE 16 -1 (-6800 2775)(-6800 2650);
WIRE 16 -1 (-7525 4475)(-7525 4350);
WIRE 16 -1 (-4225 1150)(-4225 1075);
WIRE 16 -1 (-7475 1575)(-7475 1450);
WIRE 16 -1 (-4275 4025)(-4275 3950);
WIRE 16 -1 (-6975 4550)(-7200 4550);
WIRE 16 -1 (-7200 4550)(-7200 4425);
WIRE 16 -1 (-7200 5100)(-7200 5050);
WIRE 16 -1 (-6850 5675)(-6850 5550);
WIRE 16 -1 (-6925 1650)(-7150 1650);
WIRE 16 -1 (-7150 1650)(-7150 1525);
WIRE 16 -1 (-7150 2200)(-7150 2150);
WIRE 16 -1 (-7475 1775)(-7475 1850);
WIRE 16 -1 (-6100 1850)(-7475 1850);
FORCEPROP 2 LAST SIG_NAME PVDDCR_CPU0_P1_VCCS
J 2
(-6160 1860);
DISPLAY 0.489362 (-6160 1860);
WIRE 16 -1 (-7650 1850)(-7475 1850);
WIRE 16 -1 (-6100 1950)(-6750 1950);
FORCEPROP 2 LAST SIG_NAME PVDDCR_CPU0_P1_IMON6
J 2
(-6160 1960);
DISPLAY 0.489362 (-6160 1960);
WIRE 16 -1 (-6100 1350)(-6700 1350);
FORCEPROP 2 LAST SIG_NAME PVDDCR_CPU0_P1_PWM6
J 2
(-6160 1360);
DISPLAY 0.489362 (-6160 1360);
WIRE 16 -1 (-6100 1450)(-6725 1450);
FORCEPROP 2 LAST SIG_NAME PVDDCR_CPU0_P1_TEMP0
J 2
(-6160 1460);
DISPLAY 0.489362 (-6160 1460);
WIRE 16 -1 (-6100 1700)(-6550 1700);
FORCEPROP 2 LAST SIG_NAME NC_PVDDCR_CPU0_P1_DNC6
J 2
(-6160 1710);
DISPLAY 0.489362 (-6160 1710);
FORCEPROP 2 LASTPROP $XRERR UNIQUE?
J 0
(-6790 1700);
DISPLAY 0.638298 (-6790 1700);
PAINT MONO (-6790 1700);
DISPLAY INVISIBLE (-6790 1700);
WIRE 16 -1 (-6725 1650)(-6100 1650);
FORCEPROP 2 LAST SIG_NAME PVDDCR_CPU0_P1_LSET6
J 2
(-6160 1660);
DISPLAY 0.489362 (-6160 1660);
FORCEPROP 2 LASTPROP $XRERR UNIQUE?
J 0
(-6400 1660);
DISPLAY 0.638298 (-6400 1660);
PAINT MONO (-6400 1660);
DISPLAY INVISIBLE (-6400 1660);
WIRE 16 -1 (-7150 2750)(-7150 2475);
WIRE 16 -1 (-7150 2475)(-6675 2475);
WIRE 16 -1 (-7150 2475)(-7150 2400);
WIRE 16 -1 (-6675 2475)(-6675 2300);
FORCEPROP 2 LAST SIG_NAME PVDDCR_CPU0_P1_VCC6
J 2
(-6160 2310);
DISPLAY 0.489362 (-6160 2310);
FORCEPROP 2 LASTPROP $XRERR UNIQUE?
J 0
(-6400 2310);
DISPLAY 0.638298 (-6400 2310);
PAINT MONO (-6400 2310);
DISPLAY INVISIBLE (-6400 2310);
WIRE 16 -1 (-6675 2300)(-6100 2300);
WIRE 16 -1 (-6675 2300)(-6675 2100);
WIRE 16 -1 (-6675 2100)(-6100 2100);
WIRE 16 -1 (-6150 4250)(-6750 4250);
FORCEPROP 2 LAST SIG_NAME PVDDCR_CPU0_P1_PWM5
J 2
(-6210 4260);
DISPLAY 0.489362 (-6210 4260);
WIRE 16 -1 (-5250 1600)(-4725 1600);
FORCEPROP 2 LAST SIG_NAME NC_PVDDCR_CPU0_P1_GL2_6
J 0
(-5135 1610);
DISPLAY 0.489362 (-5135 1610);
FORCEPROP 2 LASTPROP $XRERR UNIQUE?
J 0
(-4695 1600);
DISPLAY 0.638298 (-4695 1600);
PAINT MONO (-4695 1600);
DISPLAY INVISIBLE (-4695 1600);
WIRE 16 -1 (-5250 1650)(-4725 1650);
FORCEPROP 2 LAST SIG_NAME NC_PVDDCR_CPU0_P1_GL1_6
J 0
(-5135 1660);
DISPLAY 0.489362 (-5135 1660);
FORCEPROP 2 LASTPROP $XRERR UNIQUE?
J 0
(-4695 1650);
DISPLAY 0.638298 (-4695 1650);
PAINT MONO (-4695 1650);
DISPLAY INVISIBLE (-4695 1650);
WIRE 16 -1 (-4225 1650)(-4225 1350);
FORCEPROP 2 LAST SIG_NAME SW_PVDDCR_CPU0_P1_SW6_RC
J 0
(-4185 1460);
DISPLAY 0.489362 (-4185 1460);
FORCEPROP 2 LASTPROP $XRERR UNIQUE?
J 0
(-4425 1460);
DISPLAY 0.638298 (-4425 1460);
PAINT MONO (-4425 1460);
DISPLAY INVISIBLE (-4425 1460);
WIRE 16 -1 (-6150 4850)(-6800 4850);
FORCEPROP 2 LAST SIG_NAME PVDDCR_CPU0_P1_IMON5
J 2
(-6210 4860);
DISPLAY 0.489362 (-6210 4860);
WIRE 16 -1 (-6775 4550)(-6150 4550);
FORCEPROP 2 LAST SIG_NAME PVDDCR_CPU0_P1_LSET5
J 2
(-6210 4560);
DISPLAY 0.489362 (-6210 4560);
FORCEPROP 2 LASTPROP $XRERR UNIQUE?
J 0
(-6450 4560);
DISPLAY 0.638298 (-6450 4560);
PAINT MONO (-6450 4560);
DISPLAY INVISIBLE (-6450 4560);
WIRE 16 -1 (-6150 4350)(-6775 4350);
FORCEPROP 2 LAST SIG_NAME PVDDCR_CPU0_P1_TEMP0
J 2
(-6210 4360);
DISPLAY 0.489362 (-6210 4360);
WIRE 16 -1 (-6725 5200)(-6150 5200);
WIRE 16 -1 (-6725 5375)(-6725 5200);
FORCEPROP 2 LAST SIG_NAME PVDDCR_CPU0_P1_VCC5
J 2
(-6210 5210);
DISPLAY 0.489362 (-6210 5210);
FORCEPROP 2 LASTPROP $XRERR UNIQUE?
J 0
(-6450 5210);
DISPLAY 0.638298 (-6450 5210);
PAINT MONO (-6450 5210);
DISPLAY INVISIBLE (-6450 5210);
WIRE 16 -1 (-6725 5200)(-6725 5000);
WIRE 16 -1 (-6725 5000)(-6150 5000);
WIRE 16 -1 (-7200 5375)(-6725 5375);
WIRE 16 -1 (-7200 5650)(-7200 5375);
WIRE 16 -1 (-7200 5375)(-7200 5300);
WIRE 16 -1 (-6150 4600)(-6600 4600);
FORCEPROP 2 LAST SIG_NAME NC_PVDDCR_CPU0_P1_DNC5
J 2
(-6210 4610);
DISPLAY 0.489362 (-6210 4610);
FORCEPROP 2 LASTPROP $XRERR UNIQUE?
J 0
(-6840 4600);
DISPLAY 0.638298 (-6840 4600);
PAINT MONO (-6840 4600);
DISPLAY INVISIBLE (-6840 4600);
WIRE 16 -1 (-2025 1700)(-1525 1700);
FORCEPROP 2 LAST SIG_NAME IND_CPU0_P1_CPL6
J 0
(-1935 1710);
DISPLAY 0.489362 (-1935 1710);
WIRE 16 -1 (-3325 4600)(-2875 4600);
FORCEPROP 2 LAST SIG_NAME IND_CPU0_P1_CPL6
J 0
(-3310 4610);
DISPLAY 0.489362 (-3310 4610);
WIRE 16 -1 (-2075 4600)(-1575 4600);
FORCEPROP 2 LAST SIG_NAME IND_CPU0_P1_CPL5
J 0
(-1985 4610);
DISPLAY 0.489362 (-1985 4610);
WIRE 16 -1 (-7700 4750)(-7525 4750);
WIRE 16 -1 (-6150 4750)(-7525 4750);
FORCEPROP 2 LAST SIG_NAME PVDDCR_CPU0_P1_VCCS
J 2
(-6210 4760);
DISPLAY 0.489362 (-6210 4760);
WIRE 16 -1 (-7525 4675)(-7525 4750);
WIRE 16 -1 (-4275 4550)(-4275 4225);
FORCEPROP 2 LAST SIG_NAME SW_PVDDCR_CPU0_P1_SW5_RC
J 0
(-4235 4360);
DISPLAY 0.489362 (-4235 4360);
FORCEPROP 2 LASTPROP $XRERR UNIQUE?
J 0
(-4475 4360);
DISPLAY 0.638298 (-4475 4360);
PAINT MONO (-4475 4360);
DISPLAY INVISIBLE (-4475 4360);
WIRE 16 -1 (-5300 4500)(-4775 4500);
FORCEPROP 2 LAST SIG_NAME NC_PVDDCR_CPU0_P1_GL2_5
J 0
(-5185 4510);
DISPLAY 0.489362 (-5185 4510);
FORCEPROP 2 LASTPROP $XRERR UNIQUE?
J 0
(-4745 4500);
DISPLAY 0.638298 (-4745 4500);
PAINT MONO (-4745 4500);
DISPLAY INVISIBLE (-4745 4500);
WIRE 16 -1 (-5300 4550)(-4775 4550);
FORCEPROP 2 LAST SIG_NAME NC_PVDDCR_CPU0_P1_GL1_5
J 0
(-5185 4560);
DISPLAY 0.489362 (-5185 4560);
FORCEPROP 2 LASTPROP $XRERR UNIQUE?
J 0
(-4745 4550);
DISPLAY 0.638298 (-4745 4550);
PAINT MONO (-4745 4550);
DISPLAY INVISIBLE (-4745 4550);
WIRE 16 -1 (-1325 4850)(-1175 4850);
WIRE 16 -1 (-2075 4850)(-1325 4850);
WIRE 16 -1 (-1325 4850)(-1325 3750);
WIRE 16 -1 (-1175 4850)(-750 4850);
WIRE 16 -1 (-1175 4850)(-1175 4775);
WIRE 16 -1 (-750 4950)(-750 4850);
WIRE 16 -1 (-750 4850)(-750 4775);
WIRE 16 -1 (-1325 3750)(-3825 3750);
WIRE 16 -1 (-1175 4575)(-1175 4450);
WIRE 16 -1 (-750 4450)(-1175 4450);
WIRE 16 -1 (-750 4575)(-750 4450);
WIRE 16 -1 (-750 4375)(-750 4450);
WIRE 16 -1 (-1275 1950)(-1125 1950);
WIRE 16 -1 (-2025 1950)(-1275 1950);
WIRE 16 -1 (-1275 1950)(-1275 900);
WIRE 16 -1 (-1125 1950)(-700 1950);
WIRE 16 -1 (-1125 1950)(-1125 1875);
WIRE 16 -1 (-700 2050)(-700 1950);
WIRE 16 -1 (-700 1950)(-700 1875);
WIRE 16 -1 (-1275 900)(-3725 900);
WIRE 16 -1 (-1125 1675)(-1125 1550);
WIRE 16 -1 (-700 1550)(-1125 1550);
WIRE 16 -1 (-700 1675)(-700 1550);
WIRE 16 -1 (-700 1475)(-700 1550);
WIRE 16 -1 (-6525 5500)(-6150 5500);
WIRE 16 -1 (-6525 5500)(-6525 5975);
WIRE 16 -1 (-6525 5975)(-6850 5975);
WIRE 16 -1 (-6850 5875)(-6850 5975);
WIRE 16 -1 (-6850 5975)(-7200 5975);
WIRE 16 -1 (-7200 6100)(-7200 5975);
WIRE 16 -1 (-7200 5850)(-7200 5975);
WIRE 16 -1 (-5150 4400)(-5300 4400);
WIRE 16 -1 (-5150 4400)(-5150 4350);
WIRE 16 -1 (-5150 4300)(-5150 4350);
WIRE 16 -1 (-5300 4350)(-5150 4350);
WIRE 16 -1 (-5150 4250)(-5150 4300);
WIRE 16 -1 (-5300 4300)(-5150 4300);
WIRE 16 -1 (-5150 4175)(-5150 4250);
WIRE 16 -1 (-5300 4250)(-5150 4250);
WIRE 16 -1 (-5100 1500)(-5100 1450);
WIRE 16 -1 (-5100 1500)(-5250 1500);
WIRE 16 -1 (-5100 1400)(-5100 1450);
WIRE 16 -1 (-5250 1450)(-5100 1450);
WIRE 16 -1 (-5100 1350)(-5100 1400);
WIRE 16 -1 (-5250 1400)(-5100 1400);
WIRE 16 -1 (-5100 1275)(-5100 1350);
WIRE 16 -1 (-5250 1350)(-5100 1350);
WIRE 16 -1 (-6475 2600)(-6100 2600);
WIRE 16 -1 (-6475 2600)(-6475 3075);
WIRE 16 -1 (-6475 3075)(-6800 3075);
WIRE 16 -1 (-6800 3075)(-7150 3075);
WIRE 16 -1 (-6800 2975)(-6800 3075);
WIRE 16 -1 (-7150 3200)(-7150 3075);
WIRE 16 -1 (-7150 2950)(-7150 3075);
WIRE 16 -1 (-3700 1700)(-3500 1700);
WIRE 16 -1 (-3700 1625)(-3700 1700);
WIRE 16 -1 (-4225 1850)(-4225 1950);
WIRE 16 -1 (-4225 1950)(-2825 1950);
WIRE 16 -1 (-5250 1950)(-4225 1950);
FORCEPROP 2 LAST SIG_NAME SW_PVDDCR_CPU0_P1_SW6
J 0
(-5135 1960);
DISPLAY 0.489362 (-5135 1960);
FORCEPROP 2 LASTPROP $XRERR UNIQUE?
J 0
(-5375 1960);
DISPLAY 0.638298 (-5375 1960);
PAINT MONO (-5375 1960);
DISPLAY INVISIBLE (-5375 1960);
WIRE 16 -1 (-3275 2075)(-3275 2050);
WIRE 16 -1 (-3275 2050)(-5250 2050);
FORCEPROP 2 LAST SIG_NAME SW_PVDDCR_CPU0_P1_PH6
J 0
(-5135 2060);
DISPLAY 0.489362 (-5135 2060);
FORCEPROP 2 LASTPROP $XRERR UNIQUE?
J 0
(-5375 2060);
DISPLAY 0.638298 (-5375 2060);
PAINT MONO (-5375 2060);
DISPLAY INVISIBLE (-5375 2060);
WIRE 16 -1 (-5250 1700)(-4500 1700);
WIRE 16 -1 (-4500 1700)(-4500 900);
WIRE 16 -1 (-3925 900)(-4500 900);
FORCEPROP 2 LAST SIG_NAME PVDDCR_CPU0_P1_VOS6
J 0
(-5135 1725);
DISPLAY 0.489362 (-5135 1725);
FORCEPROP 2 LASTPROP $XRERR UNIQUE?
J 0
(-5375 1725);
DISPLAY 0.638298 (-5375 1725);
PAINT MONO (-5375 1725);
DISPLAY INVISIBLE (-5375 1725);
WIRE 16 -1 (-3300 1700)(-2825 1700);
WIRE 16 -1 (-4150 2300)(-3275 2300);
FORCEPROP 2 LAST SIG_NAME SW_PVDDCR_CPU0_P1_BOOT6_RC
J 2
(-3310 2310);
DISPLAY 0.489362 (-3310 2310);
FORCEPROP 2 LASTPROP $XRERR UNIQUE?
J 0
(-3550 2310);
DISPLAY 0.638298 (-3550 2310);
PAINT MONO (-3550 2310);
DISPLAY INVISIBLE (-3550 2310);
WIRE 16 -1 (-3275 2300)(-3275 2275);
WIRE 16 -1 (-5250 2300)(-4350 2300);
FORCEPROP 2 LAST SIG_NAME SW_PVDDCR_CPU0_P1_BOOT6
J 0
(-5135 2310);
DISPLAY 0.489362 (-5135 2310);
FORCEPROP 2 LASTPROP $XRERR UNIQUE?
J 0
(-5375 2310);
DISPLAY 0.638298 (-5375 2310);
PAINT MONO (-5375 2310);
DISPLAY INVISIBLE (-5375 2310);
WIRE 16 -1 (-4200 5200)(-3325 5200);
FORCEPROP 2 LAST SIG_NAME SW_PVDDCR_CPU0_P1_BOOT5_RC
J 2
(-3360 5210);
DISPLAY 0.489362 (-3360 5210);
FORCEPROP 2 LASTPROP $XRERR UNIQUE?
J 0
(-3600 5210);
DISPLAY 0.638298 (-3600 5210);
PAINT MONO (-3600 5210);
DISPLAY INVISIBLE (-3600 5210);
WIRE 16 -1 (-3325 5200)(-3325 5175);
WIRE 16 -1 (-5300 5200)(-4400 5200);
FORCEPROP 2 LAST SIG_NAME SW_PVDDCR_CPU0_P1_BOOT5
J 0
(-5185 5210);
DISPLAY 0.489362 (-5185 5210);
FORCEPROP 2 LASTPROP $XRERR UNIQUE?
J 0
(-5425 5210);
DISPLAY 0.638298 (-5425 5210);
PAINT MONO (-5425 5210);
DISPLAY INVISIBLE (-5425 5210);
WIRE 16 -1 (-3925 5625)(-3925 5500);
WIRE 16 -1 (-3625 5500)(-3925 5500);
WIRE 16 -1 (-4250 5500)(-3925 5500);
WIRE 16 -1 (-4250 5625)(-4250 5500);
WIRE 16 -1 (-4575 5500)(-4250 5500);
WIRE 16 -1 (-3625 5625)(-3625 5500);
WIRE 16 -1 (-3625 5500)(-3625 5425);
WIRE 16 -1 (-4575 5625)(-4575 5500);
WIRE 16 -1 (-4950 5500)(-4575 5500);
WIRE 16 -1 (-4950 5625)(-4950 5500);
WIRE 16 -1 (-3625 5975)(-3625 5900);
WIRE 16 -1 (-3625 5900)(-3625 5825);
WIRE 16 -1 (-3925 5900)(-3625 5900);
WIRE 16 -1 (-3925 5900)(-3925 5825);
WIRE 16 -1 (-4250 5900)(-3925 5900);
WIRE 16 -1 (-4250 5825)(-4250 5900);
WIRE 16 -1 (-4575 5900)(-4250 5900);
WIRE 16 -1 (-4575 5825)(-4575 5900);
WIRE 16 -1 (-4950 5900)(-4575 5900);
WIRE 16 -1 (-4950 5825)(-4950 5900);
WIRE 16 -1 (-5200 5900)(-4950 5900);
WIRE 16 -1 (-5200 5900)(-5200 5500);
WIRE 16 -1 (-5200 5500)(-5200 5450);
WIRE 16 -1 (-5300 5500)(-5200 5500);
WIRE 16 -1 (-5200 5450)(-5300 5450);
WIRE 16 -1 (-3325 4975)(-3325 4950);
WIRE 16 -1 (-3325 4950)(-5300 4950);
FORCEPROP 2 LAST SIG_NAME SW_PVDDCR_CPU0_P1_PH5
J 0
(-5185 4960);
DISPLAY 0.489362 (-5185 4960);
FORCEPROP 2 LASTPROP $XRERR UNIQUE?
J 0
(-5425 4960);
DISPLAY 0.638298 (-5425 4960);
PAINT MONO (-5425 4960);
DISPLAY INVISIBLE (-5425 4960);
WIRE 16 -1 (-5300 4850)(-4275 4850);
FORCEPROP 2 LAST SIG_NAME SW_PVDDCR_CPU0_P1_SW5
J 0
(-5185 4860);
DISPLAY 0.489362 (-5185 4860);
FORCEPROP 2 LASTPROP $XRERR UNIQUE?
J 0
(-5425 4860);
DISPLAY 0.638298 (-5425 4860);
PAINT MONO (-5425 4860);
DISPLAY INVISIBLE (-5425 4860);
WIRE 16 -1 (-4275 4850)(-2875 4850);
WIRE 16 -1 (-4275 4750)(-4275 4850);
WIRE 16 -1 (-4025 3750)(-4550 3750);
FORCEPROP 2 LAST SIG_NAME PVDDCR_CPU0_P1_VOS5
J 0
(-5185 4625);
DISPLAY 0.489362 (-5185 4625);
FORCEPROP 2 LASTPROP $XRERR UNIQUE?
J 0
(-5425 4625);
DISPLAY 0.638298 (-5425 4625);
PAINT MONO (-5425 4625);
DISPLAY INVISIBLE (-5425 4625);
WIRE 16 -1 (-4550 3750)(-4550 4600);
WIRE 16 -1 (-5300 4600)(-4550 4600);
WIRE 16 -1 (-3575 3075)(-3575 3000);
WIRE 16 -1 (-3575 3000)(-3575 2925);
WIRE 16 -1 (-3875 3000)(-3575 3000);
WIRE 16 -1 (-3875 3000)(-3875 2925);
WIRE 16 -1 (-4200 3000)(-3875 3000);
WIRE 16 -1 (-4200 2925)(-4200 3000);
WIRE 16 -1 (-4525 3000)(-4200 3000);
WIRE 16 -1 (-4525 2925)(-4525 3000);
WIRE 16 -1 (-4900 3000)(-4525 3000);
WIRE 16 -1 (-4900 2925)(-4900 3000);
WIRE 16 -1 (-5150 3000)(-4900 3000);
WIRE 16 -1 (-5150 3000)(-5150 2600);
WIRE 16 -1 (-5250 2600)(-5150 2600);
WIRE 16 -1 (-5150 2600)(-5150 2550);
WIRE 16 -1 (-5150 2550)(-5250 2550);
WIRE 16 -1 (-4900 2725)(-4900 2600);
WIRE 16 -1 (-4900 2600)(-4525 2600);
WIRE 16 -1 (-4525 2600)(-4200 2600);
WIRE 16 -1 (-4525 2725)(-4525 2600);
WIRE 16 -1 (-4200 2600)(-3875 2600);
WIRE 16 -1 (-4200 2725)(-4200 2600);
WIRE 16 -1 (-3575 2600)(-3875 2600);
WIRE 16 -1 (-3875 2725)(-3875 2600);
WIRE 16 -1 (-3575 2725)(-3575 2600);
WIRE 16 -1 (-3575 2600)(-3575 2525);
DOT 1 (-3625 5900);
DOT 1 (-750 4850);
DOT 1 (-750 4450);
DOT 1 (-1325 4850);
DOT 1 (-1175 4850);
DOT 1 (-3625 5500);
DOT 1 (-700 1950);
DOT 1 (-700 1550);
DOT 1 (-1125 1950);
DOT 1 (-1275 1950);
DOT 1 (-3575 3000);
DOT 1 (-3575 2600);
DOT 1 (-3925 5900);
DOT 1 (-4250 5900);
DOT 1 (-4575 5900);
DOT 1 (-4250 5500);
DOT 1 (-4275 4850);
DOT 1 (-4950 5900);
DOT 1 (-5200 5500);
DOT 1 (-5150 4350);
DOT 1 (-6725 5200);
DOT 1 (-6850 5975);
DOT 1 (-7200 5975);
DOT 1 (-7200 5375);
DOT 1 (-7525 4750);
DOT 1 (-5150 4300);
DOT 1 (-3875 3000);
DOT 1 (-4200 3000);
DOT 1 (-4200 2600);
DOT 1 (-4525 3000);
DOT 1 (-4525 2600);
DOT 1 (-5150 4250);
DOT 1 (-4900 3000);
DOT 1 (-5150 2600);
DOT 1 (-4225 1950);
DOT 1 (-5100 1450);
DOT 1 (-5100 1400);
DOT 1 (-5100 1350);
DOT 1 (-6675 2300);
DOT 1 (-6800 3075);
DOT 1 (-7150 3075);
DOT 1 (-7150 2475);
DOT 1 (-7475 1850);
DOT 1 (-3925 5500);
DOT 1 (-4575 5500);
DOT 1 (-3875 2600);
FORCENOTE
PVDDCR_CPU0_P1_PHASE5
(-6300 6250) 0;
DISPLAY LEFT (-6300 6250);
DISPLAY 1.595745 (-6300 6250);
PAINT WHITE (-6300 6250);
FORCENOTE
DCR=2-3,0.27M OHM
(-2075 4975) 0;
DISPLAY LEFT (-2075 4975);
DISPLAY 0.638298 (-2075 4975);
PAINT WHITE (-2075 4975);
FORCENOTE
DCR=1-4,0.105M OHM
(-2075 5025) 0;
DISPLAY LEFT (-2075 5025);
DISPLAY 0.638298 (-2075 5025);
PAINT WHITE (-2075 5025);
FORCENOTE
2ND=CV+15^0TZ01
(-2075 4925) 0;
DISPLAY LEFT (-2075 4925);
DISPLAY 0.638298 (-2075 4925);
PAINT WHITE (-2075 4925);
FORCENOTE
11.0*7.5*12.5
(-2075 5075) 0;
DISPLAY LEFT (-2075 5075);
DISPLAY 0.638298 (-2075 5075);
PAINT WHITE (-2075 5075);
FORCENOTE
PGL6303.151HLT
(-2075 5175) 0;
DISPLAY LEFT (-2075 5175);
DISPLAY 0.638298 (-2075 5175);
PAINT WHITE (-2075 5175);
FORCENOTE
ISAT:70A@100C
(-2075 5125) 0;
DISPLAY LEFT (-2075 5125);
DISPLAY 0.638298 (-2075 5125);
PAINT WHITE (-2075 5125);
FORCENOTE
DCR=2-3,0.27M OHM
(-2025 2075) 0;
DISPLAY LEFT (-2025 2075);
DISPLAY 0.638298 (-2025 2075);
PAINT WHITE (-2025 2075);
FORCENOTE
2ND=CV+15^0TZ01
(-2025 2025) 0;
DISPLAY LEFT (-2025 2025);
DISPLAY 0.638298 (-2025 2025);
PAINT WHITE (-2025 2025);
FORCENOTE
PGL6303.151HLT
(-2025 2275) 0;
DISPLAY LEFT (-2025 2275);
DISPLAY 0.638298 (-2025 2275);
PAINT WHITE (-2025 2275);
FORCENOTE
ISAT:70A@100C
(-2025 2225) 0;
DISPLAY LEFT (-2025 2225);
DISPLAY 0.638298 (-2025 2225);
PAINT WHITE (-2025 2225);
FORCENOTE
11.0*7.5*12.5
(-2025 2175) 0;
DISPLAY LEFT (-2025 2175);
DISPLAY 0.638298 (-2025 2175);
PAINT WHITE (-2025 2175);
FORCENOTE
DCR=1-4,0.105M OHM
(-2025 2125) 0;
DISPLAY LEFT (-2025 2125);
DISPLAY 0.638298 (-2025 2125);
PAINT WHITE (-2025 2125);
FORCENOTE
PVDDCR_CPU0_P1_PHASE6
(-6250 3350) 0;
DISPLAY LEFT (-6250 3350);
DISPLAY 1.595745 (-6250 3350);
PAINT WHITE (-6250 3350);
FORCENOTE
PGL6312.121AHLT
(-3575 1650) 0;
DISPLAY LEFT (-3575 1650);
DISPLAY 0.638298 (-3575 1650);
PAINT WHITE (-3575 1650);
FORCENOTE
DCR=0.17M OHM
(-3575 1500) 0;
DISPLAY LEFT (-3575 1500);
DISPLAY 0.638298 (-3575 1500);
PAINT WHITE (-3575 1500);
FORCENOTE
ISAT:60A@100C
(-3575 1600) 0;
DISPLAY LEFT (-3575 1600);
DISPLAY 0.638298 (-3575 1600);
PAINT WHITE (-3575 1600);
FORCENOTE
2ND=CV+12^0EZ04
(-3575 1450) 0;
DISPLAY LEFT (-3575 1450);
DISPLAY 0.638298 (-3575 1450);
PAINT WHITE (-3575 1450);
FORCENOTE
6.5*6.5*10.0
(-3575 1550) 0;
DISPLAY LEFT (-3575 1550);
DISPLAY 0.638298 (-3575 1550);
PAINT WHITE (-3575 1550);
QUIT
